(kicad_sch
	(version 20250114)
	(generator "eeschema")
	(generator_version "9.0")
	(paper "A3")
	(title_block
		(title "Antmicro Baseboard for Jetson AGX Thor")
		(date "2026-02-17")
		(rev "1.1.0")
		(company "Antmicro Ltd")
		(comment 1 "www.antmicro.com")
	)
	(bus_alias "CAN"
		(members "DIN" "DOUT")
	)
	(bus_alias "CSI"
		(members "CSI0_CLK-" "CSI0_CLK+" "CSI2_CLK+" "CSI2_CLK-" "CSI4_CLK+" "CSI4_CLK-"
			"CSI6_CLK+" "CSI6_CLK-" "CSI0_D1-" "CSI0_D1+" "CSI0_D0-" "CSI0_D0+" "CSI1_D0+"
			"CSI1_D0-" "CSI1_D1-" "CSI1_D1+" "CSI2_D0-" "CSI2_D0+" "CSI2_D1-" "CSI2_D1+"
			"CSI3_D0-" "CSI3_D0+" "CSI3_D1-" "CSI3_D1+" "CSI4_D0+" "CSI4_D0-" "CSI4_D1+"
			"CSI4_D1-" "CSI5_D0+" "CSI5_D0-" "CSI5_D1+" "CSI5_D1-" "CSI6_D0+" "CSI6_D0-"
			"CSI6_D1+" "CSI6_D1-" "CSI7_D0+" "CSI7_D0-" "CSI7_D1+" "CSI7_D1-"
		)
	)
	(bus_alias "DP"
		(members "TX0+" "TX0-" "TX1+" "TX1-" "TX2+" "TX2-" "TX3+" "TX3-" "AUX+"
			"AUX-" "HPD"
		)
	)
	(bus_alias "HDMI"
		(members "D2+" "D2-" "D1+" "D1-" "D0+" "D0-" "CK+" "CK-" "SCL" "SDA" "HPD")
	)
	(bus_alias "I2C"
		(members "SDA" "SCL" "~{INT}")
	)
	(bus_alias "I2S"
		(members "CLK" "FS" "SDOUT" "SDIN")
	)
	(bus_alias "PCIe"
		(members "TX0+" "TX0-" "TX1+" "TX1-" "TX2+" "TX2-" "TX3+" "TX3-" "RX0+"
			"RX0-" "RX1+" "RX1-" "RX2+" "RX2-" "RX3+" "RX3-" "~{RST}" "~{CLKREQ}"
			"CLK+" "CLK-" "TX4+" "TX4-" "TX5+" "TX5-" "TX6+" "TX6-" "TX7+" "TX7-"
			"RX4+" "RX4-" "RX5+" "RX5-" "RX6+" "RX6-" "RX7+" "RX7-"
		)
	)
	(bus_alias "RGMII"
		(members "TX0" "TX1" "TX2" "TX3" "TXC" "TX_CTL" "RX0" "RX1" "RX2" "RX3"
			"RXC" "RX_CTL" "MDC" "MDIO" "~{RESET}" "~{INT}"
		)
	)
	(bus_alias "SFI"
		(members "RX+" "RX-" "TX+" "TX-")
	)
	(bus_alias "SPI"
		(members "MISO" "MOSI" "SCK" "~{CS0}" "~{CS1}")
	)
	(bus_alias "UART"
		(members "TX" "RX" "CTS" "RTS")
	)
	(bus_alias "USB"
		(members "D+" "D-")
	)
	(text "M.2 key E"
		(exclude_from_sim no)
		(at 266.192 20.066 0)
		(effects
			(font
				(size 2.54 2.54)
				(thickness 0.508)
				(bold yes)
			)
			(justify left bottom)
		)
	)
	(text "M.2 key M"
		(exclude_from_sim no)
		(at 85.852 20.574 0)
		(effects
			(font
				(size 2.54 2.54)
				(thickness 0.508)
				(bold yes)
			)
			(justify left bottom)
		)
	)
	(text "NOTE:\nPlace bulk caps near \nthe M.2 power pads"
		(exclude_from_sim no)
		(at 139.7 96.52 0)
		(effects
			(font
				(size 1.27 1.27)
			)
			(justify left bottom)
		)
	)
	(text "2x PCIe x1, USB 2.0, I2C, UART and PCM"
		(exclude_from_sim no)
		(at 242.062 26.67 0)
		(effects
			(font
				(size 2 2)
				(thickness 0.25)
			)
			(justify left bottom)
		)
	)
	(text "SUSCLK SOURCE"
		(exclude_from_sim no)
		(at 77.724 241.808 0)
		(effects
			(font
				(size 2.54 2.54)
				(thickness 0.508)
				(bold yes)
			)
			(justify left bottom)
		)
	)
	(text "WiFi LED"
		(exclude_from_sim no)
		(at 363.728 181.356 0)
		(effects
			(font
				(size 1.27 1.27)
			)
			(justify left bottom)
		)
	)
	(text "BT LED"
		(exclude_from_sim no)
		(at 376.428 181.356 0)
		(effects
			(font
				(size 1.27 1.27)
			)
			(justify left bottom)
		)
	)
	(text "NOTE:\nNvidia Jetson AGX Thor \nsupports polarity inversion"
		(exclude_from_sim no)
		(at 87.376 192.278 0)
		(effects
			(font
				(size 1.27 1.27)
			)
			(justify left bottom)
		)
	)
	(text "PCIe x4"
		(exclude_from_sim no)
		(at 87.884 26.162 0)
		(effects
			(font
				(size 2 2)
				(thickness 0.25)
			)
			(justify left bottom)
		)
	)
	(junction
		(at 167.64 99.06)
		(diameter 0)
		(color 0 0 0 0)
	)
	(junction
		(at 83.82 102.87)
		(diameter 0)
		(color 0 0 0 0)
	)
	(junction
		(at 137.16 99.06)
		(diameter 0)
		(color 0 0 0 0)
	)
	(junction
		(at 157.48 99.06)
		(diameter 0)
		(color 0 0 0 0)
	)
	(junction
		(at 309.88 86.36)
		(diameter 0)
		(color 0 0 0 0)
	)
	(junction
		(at 132.08 99.06)
		(diameter 0)
		(color 0 0 0 0)
	)
	(junction
		(at 100.33 262.89)
		(diameter 0)
		(color 0 0 0 0)
	)
	(junction
		(at 246.38 86.36)
		(diameter 0)
		(color 0 0 0 0)
	)
	(junction
		(at 83.82 95.25)
		(diameter 0)
		(color 0 0 0 0)
	)
	(junction
		(at 318.77 86.36)
		(diameter 0)
		(color 0 0 0 0)
	)
	(junction
		(at 93.98 262.89)
		(diameter 0)
		(color 0 0 0 0)
	)
	(junction
		(at 255.27 96.52)
		(diameter 0)
		(color 0 0 0 0)
	)
	(junction
		(at 132.08 180.34)
		(diameter 0)
		(color 0 0 0 0)
	)
	(junction
		(at 327.66 86.36)
		(diameter 0)
		(color 0 0 0 0)
	)
	(junction
		(at 300.99 86.36)
		(diameter 0)
		(color 0 0 0 0)
	)
	(junction
		(at 92.71 105.41)
		(diameter 0)
		(color 0 0 0 0)
	)
	(junction
		(at 246.38 93.98)
		(diameter 0)
		(color 0 0 0 0)
	)
	(junction
		(at 147.32 99.06)
		(diameter 0)
		(color 0 0 0 0)
	)
	(junction
		(at 298.45 198.12)
		(diameter 0)
		(color 0 0 0 0)
	)
	(no_connect
		(at 262.89 152.4)
	)
	(no_connect
		(at 262.89 195.58)
	)
	(no_connect
		(at 293.37 160.02)
	)
	(no_connect
		(at 262.89 134.62)
	)
	(no_connect
		(at 262.89 165.1)
	)
	(no_connect
		(at 262.89 154.94)
	)
	(no_connect
		(at 262.89 180.34)
	)
	(no_connect
		(at 293.37 121.92)
	)
	(no_connect
		(at 293.37 124.46)
	)
	(no_connect
		(at 293.37 139.7)
	)
	(no_connect
		(at 262.89 142.24)
	)
	(no_connect
		(at 293.37 162.56)
	)
	(no_connect
		(at 262.89 198.12)
	)
	(no_connect
		(at 262.89 193.04)
	)
	(no_connect
		(at 262.89 127)
	)
	(no_connect
		(at 293.37 173.99)
	)
	(no_connect
		(at 293.37 147.32)
	)
	(no_connect
		(at 262.89 162.56)
	)
	(no_connect
		(at 262.89 187.96)
	)
	(no_connect
		(at 262.89 182.88)
	)
	(no_connect
		(at 293.37 171.45)
	)
	(no_connect
		(at 262.89 144.78)
	)
	(no_connect
		(at 262.89 137.16)
	)
	(no_connect
		(at 293.37 157.48)
	)
	(no_connect
		(at 262.89 129.54)
	)
	(no_connect
		(at 262.89 185.42)
	)
	(no_connect
		(at 262.89 167.64)
	)
	(no_connect
		(at 293.37 142.24)
	)
	(no_connect
		(at 262.89 149.86)
	)
	(no_connect
		(at 262.89 190.5)
	)
	(no_connect
		(at 293.37 168.91)
	)
	(no_connect
		(at 293.37 137.16)
	)
	(no_connect
		(at 262.89 160.02)
	)
	(no_connect
		(at 293.37 144.78)
	)
	(bus_entry
		(at 346.71 128.27)
		(size -1.27 1.27)
		(stroke
			(width 0)
			(type default)
		)
	)
	(bus_entry
		(at 36.83 140.97)
		(size 1.27 1.27)
		(stroke
			(width 0)
			(type default)
		)
	)
	(bus_entry
		(at 36.83 163.83)
		(size 1.27 1.27)
		(stroke
			(width 0)
			(type default)
		)
	)
	(bus_entry
		(at 207.01 173.99)
		(size 1.27 1.27)
		(stroke
			(width 0)
			(type default)
		)
	)
	(bus_entry
		(at 36.83 148.59)
		(size 1.27 1.27)
		(stroke
			(width 0)
			(type default)
		)
	)
	(bus_entry
		(at 199.39 105.41)
		(size 1.27 1.27)
		(stroke
			(width 0)
			(type default)
		)
	)
	(bus_entry
		(at 346.71 130.81)
		(size -1.27 1.27)
		(stroke
			(width 0)
			(type default)
		)
	)
	(bus_entry
		(at 36.83 161.29)
		(size 1.27 1.27)
		(stroke
			(width 0)
			(type default)
		)
	)
	(bus_entry
		(at 36.83 153.67)
		(size 1.27 1.27)
		(stroke
			(width 0)
			(type default)
		)
	)
	(bus_entry
		(at 199.39 120.65)
		(size 1.27 1.27)
		(stroke
			(width 0)
			(type default)
		)
	)
	(bus_entry
		(at 36.83 116.84)
		(size 1.27 1.27)
		(stroke
			(width 0)
			(type default)
		)
	)
	(bus_entry
		(at 36.83 114.3)
		(size 1.27 1.27)
		(stroke
			(width 0)
			(type default)
		)
	)
	(bus_entry
		(at 199.39 92.71)
		(size 1.27 1.27)
		(stroke
			(width 0)
			(type default)
		)
	)
	(bus_entry
		(at 199.39 102.87)
		(size 1.27 1.27)
		(stroke
			(width 0)
			(type default)
		)
	)
	(bus_entry
		(at 199.39 113.03)
		(size 1.27 1.27)
		(stroke
			(width 0)
			(type default)
		)
	)
	(bus_entry
		(at 36.83 146.05)
		(size 1.27 1.27)
		(stroke
			(width 0)
			(type default)
		)
	)
	(bus_entry
		(at 199.39 110.49)
		(size 1.27 1.27)
		(stroke
			(width 0)
			(type default)
		)
	)
	(bus_entry
		(at 36.83 171.45)
		(size 1.27 1.27)
		(stroke
			(width 0)
			(type default)
		)
	)
	(bus_entry
		(at 36.83 179.07)
		(size 1.27 1.27)
		(stroke
			(width 0)
			(type default)
		)
	)
	(bus_entry
		(at 36.83 133.35)
		(size 1.27 1.27)
		(stroke
			(width 0)
			(type default)
		)
	)
	(bus_entry
		(at 36.83 130.81)
		(size 1.27 1.27)
		(stroke
			(width 0)
			(type default)
		)
	)
	(bus_entry
		(at 36.83 104.14)
		(size 1.27 1.27)
		(stroke
			(width 0)
			(type default)
		)
	)
	(bus_entry
		(at 36.83 123.19)
		(size 1.27 1.27)
		(stroke
			(width 0)
			(type default)
		)
	)
	(bus_entry
		(at 36.83 176.53)
		(size 1.27 1.27)
		(stroke
			(width 0)
			(type default)
		)
	)
	(bus_entry
		(at 36.83 138.43)
		(size 1.27 1.27)
		(stroke
			(width 0)
			(type default)
		)
	)
	(bus_entry
		(at 199.39 118.11)
		(size 1.27 1.27)
		(stroke
			(width 0)
			(type default)
		)
	)
	(bus_entry
		(at 36.83 168.91)
		(size 1.27 1.27)
		(stroke
			(width 0)
			(type default)
		)
	)
	(bus_entry
		(at 36.83 101.6)
		(size 1.27 1.27)
		(stroke
			(width 0)
			(type default)
		)
	)
	(bus_entry
		(at 36.83 125.73)
		(size 1.27 1.27)
		(stroke
			(width 0)
			(type default)
		)
	)
	(bus_entry
		(at 207.01 171.45)
		(size 1.27 1.27)
		(stroke
			(width 0)
			(type default)
		)
	)
	(bus_entry
		(at 199.39 95.25)
		(size 1.27 1.27)
		(stroke
			(width 0)
			(type default)
		)
	)
	(bus_entry
		(at 36.83 156.21)
		(size 1.27 1.27)
		(stroke
			(width 0)
			(type default)
		)
	)
	(wire
		(pts
			(xy 246.38 85.09) (xy 246.38 86.36)
		)
		(stroke
			(width 0)
			(type default)
		)
	)
	(wire
		(pts
			(xy 130.81 180.34) (xy 132.08 180.34)
		)
		(stroke
			(width 0)
			(type default)
		)
	)
	(wire
		(pts
			(xy 101.6 267.97) (xy 100.33 267.97)
		)
		(stroke
			(width 0)
			(type default)
		)
	)
	(bus
		(pts
			(xy 36.83 153.67) (xy 36.83 156.21)
		)
		(stroke
			(width 0)
			(type default)
		)
	)
	(wire
		(pts
			(xy 327.66 83.82) (xy 327.66 86.36)
		)
		(stroke
			(width 0)
			(type default)
		)
	)
	(wire
		(pts
			(xy 375.92 170.18) (xy 375.92 171.45)
		)
		(stroke
			(width 0)
			(type default)
		)
	)
	(bus
		(pts
			(xy 33.02 100.33) (xy 35.56 100.33)
		)
		(stroke
			(width 0)
			(type default)
		)
	)
	(bus
		(pts
			(xy 36.83 133.35) (xy 36.83 138.43)
		)
		(stroke
			(width 0)
			(type default)
		)
	)
	(wire
		(pts
			(xy 99.06 118.11) (xy 100.33 118.11)
		)
		(stroke
			(width 0)
			(type default)
		)
	)
	(bus
		(pts
			(xy 36.83 163.83) (xy 36.83 168.91)
		)
		(stroke
			(width 0)
			(type default)
		)
	)
	(bus
		(pts
			(xy 199.39 95.25) (xy 199.39 102.87)
		)
		(stroke
			(width 0)
			(type default)
		)
	)
	(wire
		(pts
			(xy 261.62 104.14) (xy 262.89 104.14)
		)
		(stroke
			(width 0)
			(type default)
		)
	)
	(wire
		(pts
			(xy 96.52 147.32) (xy 99.06 149.86)
		)
		(stroke
			(width 0)
			(type default)
		)
	)
	(wire
		(pts
			(xy 96.52 214.63) (xy 97.79 214.63)
		)
		(stroke
			(width 0)
			(type default)
		)
	)
	(wire
		(pts
			(xy 293.37 132.08) (xy 318.77 132.08)
		)
		(stroke
			(width 0)
			(type default)
		)
	)
	(wire
		(pts
			(xy 309.88 95.25) (xy 309.88 93.98)
		)
		(stroke
			(width 0)
			(type default)
		)
	)
	(wire
		(pts
			(xy 298.45 195.58) (xy 298.45 198.12)
		)
		(stroke
			(width 0)
			(type default)
		)
	)
	(bus
		(pts
			(xy 199.39 110.49) (xy 199.39 113.03)
		)
		(stroke
			(width 0)
			(type default)
		)
	)
	(wire
		(pts
			(xy 99.06 149.86) (xy 100.33 149.86)
		)
		(stroke
			(width 0)
			(type default)
		)
	)
	(bus
		(pts
			(xy 36.83 130.81) (xy 36.83 133.35)
		)
		(stroke
			(width 0)
			(type default)
		)
	)
	(wire
		(pts
			(xy 130.81 102.87) (xy 132.08 102.87)
		)
		(stroke
			(width 0)
			(type default)
		)
	)
	(bus
		(pts
			(xy 36.83 148.59) (xy 36.83 153.67)
		)
		(stroke
			(width 0)
			(type default)
		)
	)
	(wire
		(pts
			(xy 130.81 129.54) (xy 147.32 129.54)
		)
		(stroke
			(width 0)
			(type default)
		)
	)
	(wire
		(pts
			(xy 38.1 132.08) (xy 100.33 132.08)
		)
		(stroke
			(width 0)
			(type default)
		)
	)
	(wire
		(pts
			(xy 38.1 115.57) (xy 96.52 115.57)
		)
		(stroke
			(width 0)
			(type default)
		)
	)
	(wire
		(pts
			(xy 132.08 102.87) (xy 132.08 99.06)
		)
		(stroke
			(width 0)
			(type default)
		)
	)
	(wire
		(pts
			(xy 285.75 234.95) (xy 285.75 236.22)
		)
		(stroke
			(width 0)
			(type default)
		)
	)
	(bus
		(pts
			(xy 36.83 146.05) (xy 36.83 148.59)
		)
		(stroke
			(width 0)
			(type default)
		)
	)
	(wire
		(pts
			(xy 96.52 154.94) (xy 99.06 157.48)
		)
		(stroke
			(width 0)
			(type default)
		)
	)
	(wire
		(pts
			(xy 293.37 184.15) (xy 375.92 184.15)
		)
		(stroke
			(width 0)
			(type default)
		)
	)
	(wire
		(pts
			(xy 246.38 92.71) (xy 246.38 93.98)
		)
		(stroke
			(width 0)
			(type default)
		)
	)
	(wire
		(pts
			(xy 147.32 99.06) (xy 147.32 100.33)
		)
		(stroke
			(width 0)
			(type default)
		)
	)
	(wire
		(pts
			(xy 38.1 157.48) (xy 64.77 157.48)
		)
		(stroke
			(width 0)
			(type default)
		)
	)
	(wire
		(pts
			(xy 83.82 93.98) (xy 83.82 95.25)
		)
		(stroke
			(width 0)
			(type default)
		)
	)
	(wire
		(pts
			(xy 259.08 106.68) (xy 261.62 104.14)
		)
		(stroke
			(width 0)
			(type default)
		)
	)
	(wire
		(pts
			(xy 63.5 124.46) (xy 100.33 124.46)
		)
		(stroke
			(width 0)
			(type default)
		)
	)
	(wire
		(pts
			(xy 99.06 162.56) (xy 100.33 162.56)
		)
		(stroke
			(width 0)
			(type default)
		)
	)
	(wire
		(pts
			(xy 38.1 124.46) (xy 58.42 124.46)
		)
		(stroke
			(width 0)
			(type default)
		)
	)
	(wire
		(pts
			(xy 200.66 93.98) (xy 224.79 93.98)
		)
		(stroke
			(width 0)
			(type default)
		)
	)
	(wire
		(pts
			(xy 229.87 96.52) (xy 255.27 96.52)
		)
		(stroke
			(width 0)
			(type default)
		)
	)
	(wire
		(pts
			(xy 99.06 165.1) (xy 100.33 165.1)
		)
		(stroke
			(width 0)
			(type default)
		)
	)
	(wire
		(pts
			(xy 226.06 111.76) (xy 259.08 111.76)
		)
		(stroke
			(width 0)
			(type default)
		)
	)
	(bus
		(pts
			(xy 203.2 170.18) (xy 205.74 170.18)
		)
		(stroke
			(width 0)
			(type default)
		)
	)
	(wire
		(pts
			(xy 69.85 142.24) (xy 96.52 142.24)
		)
		(stroke
			(width 0)
			(type default)
		)
	)
	(bus
		(pts
			(xy 36.83 125.73) (xy 36.83 130.81)
		)
		(stroke
			(width 0)
			(type default)
		)
	)
	(wire
		(pts
			(xy 38.1 147.32) (xy 96.52 147.32)
		)
		(stroke
			(width 0)
			(type default)
		)
	)
	(wire
		(pts
			(xy 92.71 105.41) (xy 100.33 105.41)
		)
		(stroke
			(width 0)
			(type default)
		)
	)
	(bus
		(pts
			(xy 199.39 105.41) (xy 199.39 110.49)
		)
		(stroke
			(width 0)
			(type default)
		)
	)
	(wire
		(pts
			(xy 232.41 114.3) (xy 259.08 114.3)
		)
		(stroke
			(width 0)
			(type default)
		)
	)
	(wire
		(pts
			(xy 63.5 139.7) (xy 96.52 139.7)
		)
		(stroke
			(width 0)
			(type default)
		)
	)
	(wire
		(pts
			(xy 309.88 86.36) (xy 309.88 88.9)
		)
		(stroke
			(width 0)
			(type default)
		)
	)
	(wire
		(pts
			(xy 293.37 198.12) (xy 298.45 198.12)
		)
		(stroke
			(width 0)
			(type default)
		)
	)
	(wire
		(pts
			(xy 38.1 127) (xy 64.77 127)
		)
		(stroke
			(width 0)
			(type default)
		)
	)
	(bus
		(pts
			(xy 36.83 114.3) (xy 36.83 116.84)
		)
		(stroke
			(width 0)
			(type default)
		)
	)
	(wire
		(pts
			(xy 167.64 99.06) (xy 157.48 99.06)
		)
		(stroke
			(width 0)
			(type default)
		)
	)
	(wire
		(pts
			(xy 96.52 162.56) (xy 99.06 165.1)
		)
		(stroke
			(width 0)
			(type default)
		)
	)
	(wire
		(pts
			(xy 38.1 165.1) (xy 96.52 165.1)
		)
		(stroke
			(width 0)
			(type default)
		)
	)
	(wire
		(pts
			(xy 293.37 106.68) (xy 318.77 106.68)
		)
		(stroke
			(width 0)
			(type default)
		)
	)
	(wire
		(pts
			(xy 200.66 114.3) (xy 227.33 114.3)
		)
		(stroke
			(width 0)
			(type default)
		)
	)
	(wire
		(pts
			(xy 96.52 149.86) (xy 99.06 147.32)
		)
		(stroke
			(width 0)
			(type default)
		)
	)
	(wire
		(pts
			(xy 246.38 93.98) (xy 262.89 93.98)
		)
		(stroke
			(width 0)
			(type default)
		)
	)
	(wire
		(pts
			(xy 132.08 140.97) (xy 132.08 142.24)
		)
		(stroke
			(width 0)
			(type default)
		)
	)
	(wire
		(pts
			(xy 93.98 262.89) (xy 93.98 261.62)
		)
		(stroke
			(width 0)
			(type default)
		)
	)
	(wire
		(pts
			(xy 293.37 129.54) (xy 318.77 129.54)
		)
		(stroke
			(width 0)
			(type default)
		)
	)
	(wire
		(pts
			(xy 38.1 142.24) (xy 64.77 142.24)
		)
		(stroke
			(width 0)
			(type default)
		)
	)
	(wire
		(pts
			(xy 69.85 172.72) (xy 100.33 172.72)
		)
		(stroke
			(width 0)
			(type default)
		)
	)
	(wire
		(pts
			(xy 130.81 132.08) (xy 147.32 132.08)
		)
		(stroke
			(width 0)
			(type default)
		)
	)
	(wire
		(pts
			(xy 132.08 99.06) (xy 137.16 99.06)
		)
		(stroke
			(width 0)
			(type default)
		)
	)
	(wire
		(pts
			(xy 38.1 105.41) (xy 62.23 105.41)
		)
		(stroke
			(width 0)
			(type default)
		)
	)
	(wire
		(pts
			(xy 327.66 86.36) (xy 327.66 88.9)
		)
		(stroke
			(width 0)
			(type default)
		)
	)
	(bus
		(pts
			(xy 36.83 104.14) (xy 36.83 114.3)
		)
		(stroke
			(width 0)
			(type default)
		)
	)
	(wire
		(pts
			(xy 208.28 172.72) (xy 229.87 172.72)
		)
		(stroke
			(width 0)
			(type default)
		)
	)
	(wire
		(pts
			(xy 284.48 234.95) (xy 285.75 234.95)
		)
		(stroke
			(width 0)
			(type default)
		)
	)
	(wire
		(pts
			(xy 132.08 154.94) (xy 132.08 157.48)
		)
		(stroke
			(width 0)
			(type default)
		)
	)
	(wire
		(pts
			(xy 200.66 96.52) (xy 224.79 96.52)
		)
		(stroke
			(width 0)
			(type default)
		)
	)
	(wire
		(pts
			(xy 259.08 104.14) (xy 261.62 106.68)
		)
		(stroke
			(width 0)
			(type default)
		)
	)
	(bus
		(pts
			(xy 36.83 168.91) (xy 36.83 171.45)
		)
		(stroke
			(width 0)
			(type default)
		)
	)
	(wire
		(pts
			(xy 295.91 86.36) (xy 295.91 93.98)
		)
		(stroke
			(width 0)
			(type default)
		)
	)
	(bus
		(pts
			(xy 207.01 171.45) (xy 207.01 173.99)
		)
		(stroke
			(width 0)
			(type default)
		)
	)
	(bus
		(pts
			(xy 36.83 140.97) (xy 36.83 146.05)
		)
		(stroke
			(width 0)
			(type default)
		)
	)
	(bus
		(pts
			(xy 199.39 118.11) (xy 199.39 120.65)
		)
		(stroke
			(width 0)
			(type default)
		)
	)
	(wire
		(pts
			(xy 229.87 93.98) (xy 246.38 93.98)
		)
		(stroke
			(width 0)
			(type default)
		)
	)
	(wire
		(pts
			(xy 208.28 175.26) (xy 229.87 175.26)
		)
		(stroke
			(width 0)
			(type default)
		)
	)
	(wire
		(pts
			(xy 38.1 102.87) (xy 62.23 102.87)
		)
		(stroke
			(width 0)
			(type default)
		)
	)
	(wire
		(pts
			(xy 38.1 149.86) (xy 96.52 149.86)
		)
		(stroke
			(width 0)
			(type default)
		)
	)
	(bus
		(pts
			(xy 36.83 123.19) (xy 36.83 125.73)
		)
		(stroke
			(width 0)
			(type default)
		)
	)
	(wire
		(pts
			(xy 100.33 265.43) (xy 100.33 262.89)
		)
		(stroke
			(width 0)
			(type default)
		)
	)
	(wire
		(pts
			(xy 92.71 95.25) (xy 92.71 96.52)
		)
		(stroke
			(width 0)
			(type default)
		)
	)
	(wire
		(pts
			(xy 67.31 107.95) (xy 100.33 107.95)
		)
		(stroke
			(width 0)
			(type default)
		)
	)
	(wire
		(pts
			(xy 200.66 111.76) (xy 220.98 111.76)
		)
		(stroke
			(width 0)
			(type default)
		)
	)
	(wire
		(pts
			(xy 375.92 176.53) (xy 375.92 184.15)
		)
		(stroke
			(width 0)
			(type default)
		)
	)
	(bus
		(pts
			(xy 199.39 102.87) (xy 199.39 105.41)
		)
		(stroke
			(width 0)
			(type default)
		)
	)
	(wire
		(pts
			(xy 200.66 121.92) (xy 262.89 121.92)
		)
		(stroke
			(width 0)
			(type default)
		)
	)
	(wire
		(pts
			(xy 158.75 115.57) (xy 172.72 115.57)
		)
		(stroke
			(width 0)
			(type default)
		)
	)
	(polyline
		(pts
			(xy 12.7 233.68) (xy 177.8 233.68)
		)
		(stroke
			(width 0)
			(type default)
		)
	)
	(bus
		(pts
			(xy 199.39 92.71) (xy 199.39 95.25)
		)
		(stroke
			(width 0)
			(type default)
		)
	)
	(wire
		(pts
			(xy 132.08 181.61) (xy 132.08 180.34)
		)
		(stroke
			(width 0)
			(type default)
		)
	)
	(wire
		(pts
			(xy 92.71 95.25) (xy 83.82 95.25)
		)
		(stroke
			(width 0)
			(type default)
		)
	)
	(wire
		(pts
			(xy 300.99 86.36) (xy 300.99 88.9)
		)
		(stroke
			(width 0)
			(type default)
		)
	)
	(bus
		(pts
			(xy 350.52 127) (xy 347.98 127)
		)
		(stroke
			(width 0)
			(type default)
		)
	)
	(polyline
		(pts
			(xy 177.8 12.7) (xy 177.8 284.48)
		)
		(stroke
			(width 0)
			(type default)
		)
	)
	(wire
		(pts
			(xy 219.71 99.06) (xy 224.79 99.06)
		)
		(stroke
			(width 0)
			(type default)
		)
	)
	(wire
		(pts
			(xy 63.5 154.94) (xy 96.52 154.94)
		)
		(stroke
			(width 0)
			(type default)
		)
	)
	(wire
		(pts
			(xy 167.64 95.25) (xy 167.64 99.06)
		)
		(stroke
			(width 0)
			(type default)
		)
	)
	(wire
		(pts
			(xy 130.81 134.62) (xy 147.32 134.62)
		)
		(stroke
			(width 0)
			(type default)
		)
	)
	(wire
		(pts
			(xy 83.82 101.6) (xy 83.82 102.87)
		)
		(stroke
			(width 0)
			(type default)
		)
	)
	(bus
		(pts
			(xy 346.71 128.27) (xy 346.71 130.81)
		)
		(stroke
			(width 0)
			(type default)
		)
	)
	(wire
		(pts
			(xy 132.08 177.8) (xy 130.81 177.8)
		)
		(stroke
			(width 0)
			(type default)
		)
	)
	(bus
		(pts
			(xy 36.83 116.84) (xy 36.83 123.19)
		)
		(stroke
			(width 0)
			(type default)
		)
	)
	(wire
		(pts
			(xy 92.71 101.6) (xy 92.71 105.41)
		)
		(stroke
			(width 0)
			(type default)
		)
	)
	(wire
		(pts
			(xy 157.48 99.06) (xy 157.48 100.33)
		)
		(stroke
			(width 0)
			(type default)
		)
	)
	(wire
		(pts
			(xy 327.66 95.25) (xy 327.66 93.98)
		)
		(stroke
			(width 0)
			(type default)
		)
	)
	(wire
		(pts
			(xy 38.1 154.94) (xy 58.42 154.94)
		)
		(stroke
			(width 0)
			(type default)
		)
	)
	(wire
		(pts
			(xy 295.91 93.98) (xy 293.37 93.98)
		)
		(stroke
			(width 0)
			(type default)
		)
	)
	(wire
		(pts
			(xy 132.08 180.34) (xy 132.08 177.8)
		)
		(stroke
			(width 0)
			(type default)
		)
	)
	(wire
		(pts
			(xy 300.99 86.36) (xy 309.88 86.36)
		)
		(stroke
			(width 0)
			(type default)
		)
	)
	(bus
		(pts
			(xy 36.83 156.21) (xy 36.83 161.29)
		)
		(stroke
			(width 0)
			(type default)
		)
	)
	(wire
		(pts
			(xy 38.1 172.72) (xy 64.77 172.72)
		)
		(stroke
			(width 0)
			(type default)
		)
	)
	(wire
		(pts
			(xy 99.06 157.48) (xy 100.33 157.48)
		)
		(stroke
			(width 0)
			(type default)
		)
	)
	(wire
		(pts
			(xy 96.52 139.7) (xy 99.06 142.24)
		)
		(stroke
			(width 0)
			(type default)
		)
	)
	(bus
		(pts
			(xy 36.83 101.6) (xy 36.83 104.14)
		)
		(stroke
			(width 0)
			(type default)
		)
	)
	(wire
		(pts
			(xy 259.08 111.76) (xy 261.62 114.3)
		)
		(stroke
			(width 0)
			(type default)
		)
	)
	(wire
		(pts
			(xy 135.89 262.89) (xy 120.65 262.89)
		)
		(stroke
			(width 0)
			(type default)
		)
	)
	(wire
		(pts
			(xy 255.27 96.52) (xy 262.89 96.52)
		)
		(stroke
			(width 0)
			(type default)
		)
	)
	(bus
		(pts
			(xy 196.85 91.44) (xy 198.12 91.44)
		)
		(stroke
			(width 0)
			(type default)
		)
	)
	(wire
		(pts
			(xy 93.98 262.89) (xy 100.33 262.89)
		)
		(stroke
			(width 0)
			(type default)
		)
	)
	(wire
		(pts
			(xy 38.1 134.62) (xy 100.33 134.62)
		)
		(stroke
			(width 0)
			(type default)
		)
	)
	(wire
		(pts
			(xy 99.06 115.57) (xy 100.33 115.57)
		)
		(stroke
			(width 0)
			(type default)
		)
	)
	(wire
		(pts
			(xy 293.37 119.38) (xy 312.42 119.38)
		)
		(stroke
			(width 0)
			(type default)
		)
	)
	(wire
		(pts
			(xy 246.38 86.36) (xy 246.38 87.63)
		)
		(stroke
			(width 0)
			(type default)
		)
	)
	(wire
		(pts
			(xy 259.08 114.3) (xy 261.62 111.76)
		)
		(stroke
			(width 0)
			(type default)
		)
	)
	(wire
		(pts
			(xy 137.16 99.06) (xy 137.16 100.33)
		)
		(stroke
			(width 0)
			(type default)
		)
	)
	(wire
		(pts
			(xy 309.88 86.36) (xy 318.77 86.36)
		)
		(stroke
			(width 0)
			(type default)
		)
	)
	(wire
		(pts
			(xy 318.77 95.25) (xy 318.77 93.98)
		)
		(stroke
			(width 0)
			(type default)
		)
	)
	(wire
		(pts
			(xy 318.77 86.36) (xy 327.66 86.36)
		)
		(stroke
			(width 0)
			(type default)
		)
	)
	(wire
		(pts
			(xy 234.95 172.72) (xy 262.89 172.72)
		)
		(stroke
			(width 0)
			(type default)
		)
	)
	(wire
		(pts
			(xy 57.15 107.95) (xy 62.23 107.95)
		)
		(stroke
			(width 0)
			(type default)
		)
	)
	(wire
		(pts
			(xy 96.52 142.24) (xy 99.06 139.7)
		)
		(stroke
			(width 0)
			(type default)
		)
	)
	(wire
		(pts
			(xy 38.1 139.7) (xy 58.42 139.7)
		)
		(stroke
			(width 0)
			(type default)
		)
	)
	(wire
		(pts
			(xy 261.62 111.76) (xy 262.89 111.76)
		)
		(stroke
			(width 0)
			(type default)
		)
	)
	(wire
		(pts
			(xy 97.79 214.63) (xy 97.79 215.9)
		)
		(stroke
			(width 0)
			(type default)
		)
	)
	(wire
		(pts
			(xy 96.52 118.11) (xy 99.06 115.57)
		)
		(stroke
			(width 0)
			(type default)
		)
	)
	(wire
		(pts
			(xy 99.06 142.24) (xy 100.33 142.24)
		)
		(stroke
			(width 0)
			(type default)
		)
	)
	(wire
		(pts
			(xy 261.62 106.68) (xy 262.89 106.68)
		)
		(stroke
			(width 0)
			(type default)
		)
	)
	(wire
		(pts
			(xy 295.91 86.36) (xy 300.99 86.36)
		)
		(stroke
			(width 0)
			(type default)
		)
	)
	(wire
		(pts
			(xy 38.1 162.56) (xy 96.52 162.56)
		)
		(stroke
			(width 0)
			(type default)
		)
	)
	(wire
		(pts
			(xy 167.64 88.9) (xy 167.64 90.17)
		)
		(stroke
			(width 0)
			(type default)
		)
	)
	(wire
		(pts
			(xy 99.06 147.32) (xy 100.33 147.32)
		)
		(stroke
			(width 0)
			(type default)
		)
	)
	(wire
		(pts
			(xy 83.82 102.87) (xy 100.33 102.87)
		)
		(stroke
			(width 0)
			(type default)
		)
	)
	(bus
		(pts
			(xy 36.83 161.29) (xy 36.83 163.83)
		)
		(stroke
			(width 0)
			(type default)
		)
	)
	(wire
		(pts
			(xy 100.33 267.97) (xy 100.33 270.51)
		)
		(stroke
			(width 0)
			(type default)
		)
	)
	(wire
		(pts
			(xy 293.37 195.58) (xy 298.45 195.58)
		)
		(stroke
			(width 0)
			(type default)
		)
	)
	(wire
		(pts
			(xy 323.85 132.08) (xy 345.44 132.08)
		)
		(stroke
			(width 0)
			(type default)
		)
	)
	(wire
		(pts
			(xy 100.33 262.89) (xy 101.6 262.89)
		)
		(stroke
			(width 0)
			(type default)
		)
	)
	(wire
		(pts
			(xy 300.99 95.25) (xy 300.99 93.98)
		)
		(stroke
			(width 0)
			(type default)
		)
	)
	(wire
		(pts
			(xy 167.64 99.06) (xy 167.64 100.33)
		)
		(stroke
			(width 0)
			(type default)
		)
	)
	(wire
		(pts
			(xy 38.1 180.34) (xy 100.33 180.34)
		)
		(stroke
			(width 0)
			(type default)
		)
	)
	(wire
		(pts
			(xy 99.06 139.7) (xy 100.33 139.7)
		)
		(stroke
			(width 0)
			(type default)
		)
	)
	(wire
		(pts
			(xy 93.98 269.24) (xy 93.98 270.51)
		)
		(stroke
			(width 0)
			(type default)
		)
	)
	(wire
		(pts
			(xy 298.45 198.12) (xy 298.45 199.39)
		)
		(stroke
			(width 0)
			(type default)
		)
	)
	(wire
		(pts
			(xy 63.5 170.18) (xy 100.33 170.18)
		)
		(stroke
			(width 0)
			(type default)
		)
	)
	(wire
		(pts
			(xy 96.52 115.57) (xy 99.06 118.11)
		)
		(stroke
			(width 0)
			(type default)
		)
	)
	(wire
		(pts
			(xy 69.85 127) (xy 100.33 127)
		)
		(stroke
			(width 0)
			(type default)
		)
	)
	(wire
		(pts
			(xy 200.66 119.38) (xy 262.89 119.38)
		)
		(stroke
			(width 0)
			(type default)
		)
	)
	(wire
		(pts
			(xy 132.08 97.79) (xy 132.08 99.06)
		)
		(stroke
			(width 0)
			(type default)
		)
	)
	(wire
		(pts
			(xy 234.95 175.26) (xy 262.89 175.26)
		)
		(stroke
			(width 0)
			(type default)
		)
	)
	(wire
		(pts
			(xy 130.81 115.57) (xy 153.67 115.57)
		)
		(stroke
			(width 0)
			(type default)
		)
	)
	(wire
		(pts
			(xy 255.27 86.36) (xy 246.38 86.36)
		)
		(stroke
			(width 0)
			(type default)
		)
	)
	(wire
		(pts
			(xy 38.1 170.18) (xy 58.42 170.18)
		)
		(stroke
			(width 0)
			(type default)
		)
	)
	(wire
		(pts
			(xy 96.52 165.1) (xy 99.06 162.56)
		)
		(stroke
			(width 0)
			(type default)
		)
	)
	(wire
		(pts
			(xy 38.1 177.8) (xy 100.33 177.8)
		)
		(stroke
			(width 0)
			(type default)
		)
	)
	(bus
		(pts
			(xy 36.83 101.6) (xy 35.56 100.33)
		)
		(stroke
			(width 0)
			(type default)
		)
	)
	(wire
		(pts
			(xy 229.87 99.06) (xy 262.89 99.06)
		)
		(stroke
			(width 0)
			(type default)
		)
	)
	(bus
		(pts
			(xy 36.83 176.53) (xy 36.83 179.07)
		)
		(stroke
			(width 0)
			(type default)
		)
	)
	(wire
		(pts
			(xy 323.85 106.68) (xy 339.09 106.68)
		)
		(stroke
			(width 0)
			(type default)
		)
	)
	(wire
		(pts
			(xy 38.1 118.11) (xy 96.52 118.11)
		)
		(stroke
			(width 0)
			(type default)
		)
	)
	(wire
		(pts
			(xy 132.08 147.32) (xy 132.08 149.86)
		)
		(stroke
			(width 0)
			(type default)
		)
	)
	(wire
		(pts
			(xy 200.66 104.14) (xy 259.08 104.14)
		)
		(stroke
			(width 0)
			(type default)
		)
	)
	(bus
		(pts
			(xy 205.74 170.18) (xy 207.01 171.45)
		)
		(stroke
			(width 0)
			(type default)
		)
	)
	(wire
		(pts
			(xy 255.27 86.36) (xy 255.27 87.63)
		)
		(stroke
			(width 0)
			(type default)
		)
	)
	(wire
		(pts
			(xy 130.81 157.48) (xy 132.08 157.48)
		)
		(stroke
			(width 0)
			(type default)
		)
	)
	(wire
		(pts
			(xy 323.85 129.54) (xy 345.44 129.54)
		)
		(stroke
			(width 0)
			(type default)
		)
	)
	(wire
		(pts
			(xy 99.06 154.94) (xy 100.33 154.94)
		)
		(stroke
			(width 0)
			(type default)
		)
	)
	(wire
		(pts
			(xy 293.37 179.07) (xy 363.22 179.07)
		)
		(stroke
			(width 0)
			(type default)
		)
	)
	(wire
		(pts
			(xy 93.98 262.89) (xy 93.98 264.16)
		)
		(stroke
			(width 0)
			(type default)
		)
	)
	(wire
		(pts
			(xy 67.31 102.87) (xy 83.82 102.87)
		)
		(stroke
			(width 0)
			(type default)
		)
	)
	(wire
		(pts
			(xy 83.82 95.25) (xy 83.82 96.52)
		)
		(stroke
			(width 0)
			(type default)
		)
	)
	(wire
		(pts
			(xy 255.27 92.71) (xy 255.27 96.52)
		)
		(stroke
			(width 0)
			(type default)
		)
	)
	(bus
		(pts
			(xy 347.98 127) (xy 346.71 128.27)
		)
		(stroke
			(width 0)
			(type default)
		)
	)
	(wire
		(pts
			(xy 261.62 114.3) (xy 262.89 114.3)
		)
		(stroke
			(width 0)
			(type default)
		)
	)
	(wire
		(pts
			(xy 96.52 157.48) (xy 99.06 154.94)
		)
		(stroke
			(width 0)
			(type default)
		)
	)
	(bus
		(pts
			(xy 199.39 113.03) (xy 199.39 118.11)
		)
		(stroke
			(width 0)
			(type default)
		)
	)
	(wire
		(pts
			(xy 157.48 99.06) (xy 147.32 99.06)
		)
		(stroke
			(width 0)
			(type default)
		)
	)
	(wire
		(pts
			(xy 200.66 106.68) (xy 259.08 106.68)
		)
		(stroke
			(width 0)
			(type default)
		)
	)
	(wire
		(pts
			(xy 67.31 105.41) (xy 92.71 105.41)
		)
		(stroke
			(width 0)
			(type default)
		)
	)
	(wire
		(pts
			(xy 101.6 265.43) (xy 100.33 265.43)
		)
		(stroke
			(width 0)
			(type default)
		)
	)
	(bus
		(pts
			(xy 36.83 171.45) (xy 36.83 176.53)
		)
		(stroke
			(width 0)
			(type default)
		)
	)
	(wire
		(pts
			(xy 69.85 157.48) (xy 96.52 157.48)
		)
		(stroke
			(width 0)
			(type default)
		)
	)
	(bus
		(pts
			(xy 198.12 91.44) (xy 199.39 92.71)
		)
		(stroke
			(width 0)
			(type default)
		)
	)
	(bus
		(pts
			(xy 36.83 138.43) (xy 36.83 140.97)
		)
		(stroke
			(width 0)
			(type default)
		)
	)
	(wire
		(pts
			(xy 147.32 99.06) (xy 137.16 99.06)
		)
		(stroke
			(width 0)
			(type default)
		)
	)
	(wire
		(pts
			(xy 363.22 170.18) (xy 363.22 171.45)
		)
		(stroke
			(width 0)
			(type default)
		)
	)
	(wire
		(pts
			(xy 363.22 176.53) (xy 363.22 179.07)
		)
		(stroke
			(width 0)
			(type default)
		)
	)
	(wire
		(pts
			(xy 318.77 86.36) (xy 318.77 88.9)
		)
		(stroke
			(width 0)
			(type default)
		)
	)
	(label "M2_M_SMB_CLK"
		(at 132.08 134.62 0)
		(effects
			(font
				(size 1.27 1.27)
			)
			(justify left bottom)
		)
	)
	(label "~{PERST_E}"
		(at 242.57 93.98 180)
		(effects
			(font
				(size 1.27 1.27)
			)
			(justify right bottom)
		)
	)
	(label "3V3_M2"
		(at 148.59 99.06 0)
		(effects
			(font
				(size 1.27 1.27)
			)
			(justify left bottom)
		)
	)
	(label "PCIe_{C5x4}.TX1-"
		(at 39.37 142.24 0)
		(effects
			(font
				(size 1.27 1.27)
			)
			(justify left bottom)
		)
	)
	(label "PCIe_{C5x4}.RX3-"
		(at 39.37 180.34 0)
		(effects
			(font
				(size 1.27 1.27)
			)
			(justify left bottom)
		)
	)
	(label "SUSCLK"
		(at 339.09 106.68 180)
		(effects
			(font
				(size 1.27 1.27)
			)
			(justify right bottom)
		)
	)
	(label "~{M2_E_ALERT}"
		(at 295.91 119.38 0)
		(effects
			(font
				(size 1.27 1.27)
			)
			(justify left bottom)
		)
	)
	(label "~{CLKREQ_M}"
		(at 80.01 105.41 180)
		(effects
			(font
				(size 1.27 1.27)
			)
			(justify right bottom)
		)
	)
	(label "M2_M_PET0_N"
		(at 82.55 127 0)
		(effects
			(font
				(size 1.27 1.27)
			)
			(justify left bottom)
		)
	)
	(label "~{PERST_M}"
		(at 80.01 102.87 180)
		(effects
			(font
				(size 1.27 1.27)
			)
			(justify right bottom)
		)
	)
	(label "~{LED_2}"
		(at 295.91 184.15 0)
		(effects
			(font
				(size 1.27 1.27)
			)
			(justify left bottom)
		)
	)
	(label "M2_M_PET0_P"
		(at 82.55 124.46 0)
		(effects
			(font
				(size 1.27 1.27)
			)
			(justify left bottom)
		)
	)
	(label "PCIe_{C5x4}.CLK+"
		(at 39.37 115.57 0)
		(effects
			(font
				(size 1.27 1.27)
			)
			(justify left bottom)
		)
	)
	(label "M2_M_SUSCLK"
		(at 146.05 115.57 180)
		(effects
			(font
				(size 1.27 1.27)
			)
			(justify right bottom)
		)
	)
	(label "PCIe_{C5x4}.RX0-"
		(at 39.37 134.62 0)
		(effects
			(font
				(size 1.27 1.27)
			)
			(justify left bottom)
		)
	)
	(label "PCIe_{C5x4}.RX1+"
		(at 39.37 147.32 0)
		(effects
			(font
				(size 1.27 1.27)
			)
			(justify left bottom)
		)
	)
	(label "PCIe_{C5x4}.TX0-"
		(at 39.37 127 0)
		(effects
			(font
				(size 1.27 1.27)
			)
			(justify left bottom)
		)
	)
	(label "PCIe_{C1x1}.TX0+"
		(at 201.93 111.76 0)
		(effects
			(font
				(size 1.27 1.27)
			)
			(justify left bottom)
		)
	)
	(label "PCIe_{C5x4}.TX3-"
		(at 39.37 172.72 0)
		(effects
			(font
				(size 1.27 1.27)
			)
			(justify left bottom)
		)
	)
	(label "M2_M_PET3_P"
		(at 82.55 170.18 0)
		(effects
			(font
				(size 1.27 1.27)
			)
			(justify left bottom)
		)
	)
	(label "PCIe_{C5x4}.RX0+"
		(at 39.37 132.08 0)
		(effects
			(font
				(size 1.27 1.27)
			)
			(justify left bottom)
		)
	)
	(label "M2_E_W_DIS_1"
		(at 295.91 129.54 0)
		(effects
			(font
				(size 1.27 1.27)
			)
			(justify left bottom)
		)
	)
	(label "PCIe_{C5x4}.TX2-"
		(at 39.37 157.48 0)
		(effects
			(font
				(size 1.27 1.27)
			)
			(justify left bottom)
		)
	)
	(label "~{CLKREQ_E}"
		(at 242.57 96.52 180)
		(effects
			(font
				(size 1.27 1.27)
			)
			(justify right bottom)
		)
	)
	(label "PCIe_{C5x4}.TX2+"
		(at 39.37 154.94 0)
		(effects
			(font
				(size 1.27 1.27)
			)
			(justify left bottom)
		)
	)
	(label "PCIe_{C5x4}.RX1-"
		(at 39.37 149.86 0)
		(effects
			(font
				(size 1.27 1.27)
			)
			(justify left bottom)
		)
	)
	(label "M2_E.W_DIS_2"
		(at 327.66 132.08 0)
		(effects
			(font
				(size 1.27 1.27)
			)
			(justify left bottom)
		)
	)
	(label "PCIe_{C5x4}.~{CLKREQ}"
		(at 39.37 105.41 0)
		(effects
			(font
				(size 1.27 1.27)
			)
			(justify left bottom)
		)
	)
	(label "WIFI_BT_USB_D_N"
		(at 243.84 175.26 0)
		(effects
			(font
				(size 1.27 1.27)
			)
			(justify left bottom)
		)
	)
	(label "M2_E_PET0_N"
		(at 246.38 114.3 0)
		(effects
			(font
				(size 1.27 1.27)
			)
			(justify left bottom)
		)
	)
	(label "~{PEWAKE_M}"
		(at 80.01 107.95 180)
		(effects
			(font
				(size 1.27 1.27)
			)
			(justify right bottom)
		)
	)
	(label "M2_M_PET2_P"
		(at 82.55 154.94 0)
		(effects
			(font
				(size 1.27 1.27)
			)
			(justify left bottom)
		)
	)
	(label "PCIe_{C5x4}.~{RST}"
		(at 39.37 102.87 0)
		(effects
			(font
				(size 1.27 1.27)
			)
			(justify left bottom)
		)
	)
	(label "SUSCLK"
		(at 135.89 262.89 180)
		(effects
			(font
				(size 1.27 1.27)
			)
			(justify right bottom)
		)
	)
	(label "PCIe_{C5x4}.RX3+"
		(at 39.37 177.8 0)
		(effects
			(font
				(size 1.27 1.27)
			)
			(justify left bottom)
		)
	)
	(label "M2_M_PET2_N"
		(at 82.55 157.48 0)
		(effects
			(font
				(size 1.27 1.27)
			)
			(justify left bottom)
		)
	)
	(label "PCIe_{C1x1}.~{RST}"
		(at 201.93 93.98 0)
		(effects
			(font
				(size 1.27 1.27)
			)
			(justify left bottom)
		)
	)
	(label "~{LED_1}"
		(at 295.91 179.07 0)
		(effects
			(font
				(size 1.27 1.27)
			)
			(justify left bottom)
		)
	)
	(label "SUSCLK"
		(at 172.72 115.57 180)
		(effects
			(font
				(size 1.27 1.27)
			)
			(justify right bottom)
		)
	)
	(label "USB3.D-"
		(at 209.55 175.26 0)
		(effects
			(font
				(size 1.27 1.27)
			)
			(justify left bottom)
		)
	)
	(label "M2_E_SUSCLK"
		(at 295.91 106.68 0)
		(effects
			(font
				(size 1.27 1.27)
			)
			(justify left bottom)
		)
	)
	(label "WIFI_BT_USB_D_P"
		(at 243.84 172.72 0)
		(effects
			(font
				(size 1.27 1.27)
			)
			(justify left bottom)
		)
	)
	(label "~{PEWAKE_E}"
		(at 242.57 99.06 180)
		(effects
			(font
				(size 1.27 1.27)
			)
			(justify right bottom)
		)
	)
	(label "M2_M_PET3_N"
		(at 82.55 172.72 0)
		(effects
			(font
				(size 1.27 1.27)
			)
			(justify left bottom)
		)
	)
	(label "PCIe_{C1x1}.TX0-"
		(at 201.93 114.3 0)
		(effects
			(font
				(size 1.27 1.27)
			)
			(justify left bottom)
		)
	)
	(label "M2_M_PET1_P"
		(at 82.55 139.7 0)
		(effects
			(font
				(size 1.27 1.27)
			)
			(justify left bottom)
		)
	)
	(label "M2_E.W_DIS_1"
		(at 327.66 129.54 0)
		(effects
			(font
				(size 1.27 1.27)
			)
			(justify left bottom)
		)
	)
	(label "PCIe_{C5x4}.RX2+"
		(at 39.37 162.56 0)
		(effects
			(font
				(size 1.27 1.27)
			)
			(justify left bottom)
		)
	)
	(label "USB3.D+"
		(at 209.55 172.72 0)
		(effects
			(font
				(size 1.27 1.27)
			)
			(justify left bottom)
		)
	)
	(label "M2_E_PET0_P"
		(at 246.38 111.76 0)
		(effects
			(font
				(size 1.27 1.27)
			)
			(justify left bottom)
		)
	)
	(label "M2_M_PET1_N"
		(at 82.55 142.24 0)
		(effects
			(font
				(size 1.27 1.27)
			)
			(justify left bottom)
		)
	)
	(label "PCIe_{C5x4}.CLK-"
		(at 39.37 118.11 0)
		(effects
			(font
				(size 1.27 1.27)
			)
			(justify left bottom)
		)
	)
	(label "PCIe_{C1x1}.CLK-"
		(at 201.93 106.68 0)
		(effects
			(font
				(size 1.27 1.27)
			)
			(justify left bottom)
		)
	)
	(label "M2_E_W_DIS_2"
		(at 295.91 132.08 0)
		(effects
			(font
				(size 1.27 1.27)
			)
			(justify left bottom)
		)
	)
	(label "PCIe_{C5x4}.TX1+"
		(at 39.37 139.7 0)
		(effects
			(font
				(size 1.27 1.27)
			)
			(justify left bottom)
		)
	)
	(label "PCIe_{C1x1}.RX0-"
		(at 201.93 121.92 0)
		(effects
			(font
				(size 1.27 1.27)
			)
			(justify left bottom)
		)
	)
	(label "~{M2_M_ALERT}"
		(at 132.08 129.54 0)
		(effects
			(font
				(size 1.27 1.27)
			)
			(justify left bottom)
		)
	)
	(label "PCIe_{C5x4}.TX0+"
		(at 39.37 124.46 0)
		(effects
			(font
				(size 1.27 1.27)
			)
			(justify left bottom)
		)
	)
	(label "PCIe_{C1x1}.CLK+"
		(at 201.93 104.14 0)
		(effects
			(font
				(size 1.27 1.27)
			)
			(justify left bottom)
		)
	)
	(label "PCIe_{C1x1}.~{CLKREQ}"
		(at 201.93 96.52 0)
		(effects
			(font
				(size 1.27 1.27)
			)
			(justify left bottom)
		)
	)
	(label "PCIe_{C5x4}.RX2-"
		(at 39.37 165.1 0)
		(effects
			(font
				(size 1.27 1.27)
			)
			(justify left bottom)
		)
	)
	(label "PCIe_{C1x1}.RX0+"
		(at 201.93 119.38 0)
		(effects
			(font
				(size 1.27 1.27)
			)
			(justify left bottom)
		)
	)
	(label "PCIe_{C5x4}.TX3+"
		(at 39.37 170.18 0)
		(effects
			(font
				(size 1.27 1.27)
			)
			(justify left bottom)
		)
	)
	(label "M2_M_SMB_DATA"
		(at 132.08 132.08 0)
		(effects
			(font
				(size 1.27 1.27)
			)
			(justify left bottom)
		)
	)
	(hierarchical_label "PCIe_{C5x4}{PCIe}"
		(shape bidirectional)
		(at 33.02 100.33 180)
		(effects
			(font
				(size 1.27 1.27)
			)
			(justify right)
		)
	)
	(hierarchical_label "PCIe_{C1x1}{PCIe}"
		(shape bidirectional)
		(at 196.85 91.44 180)
		(effects
			(font
				(size 1.27 1.27)
			)
			(justify right)
		)
	)
	(hierarchical_label "~{PEWAKE}"
		(shape output)
		(at 57.15 107.95 180)
		(effects
			(font
				(size 1.27 1.27)
			)
			(justify right)
		)
	)
	(hierarchical_label "USB3{USB}"
		(shape bidirectional)
		(at 203.2 170.18 180)
		(effects
			(font
				(size 1.27 1.27)
			)
			(justify right)
		)
	)
	(hierarchical_label "M2_E{M2_E}"
		(shape bidirectional)
		(at 350.52 127 0)
		(effects
			(font
				(size 1.27 1.27)
			)
			(justify left)
		)
	)
	(hierarchical_label "~{PEWAKE}"
		(shape output)
		(at 219.71 99.06 180)
		(effects
			(font
				(size 1.27 1.27)
			)
			(justify right)
		)
	)
	(rule_area
		(polyline
			(pts
				(xy 243.84 177.8) (xy 204.47 177.8) (xy 204.47 168.91) (xy 243.8399 168.91)
			)
			(stroke
				(width 0)
				(type dash)
			)
			(fill
				(type none)
			)
		)
	)
	(rule_area
		(polyline
			(pts
				(xy 38.1 113.03) (xy 38.1 181.61) (xy 81.28 181.61) (xy 81.28 113.03)
			)
			(stroke
				(width 0)
				(type dash)
			)
			(fill
				(type none)
			)
		)
	)
	(rule_area
		(polyline
			(pts
				(xy 196.85 101.6) (xy 243.84 101.6) (xy 243.84 123.19) (xy 196.85 123.19)
			)
			(stroke
				(width 0)
				(type dash)
			)
			(fill
				(type none)
			)
		)
	)
	(netclass_flag ""
		(length 2.54)
		(shape round)
		(at 38.1 113.03 0)
		(fields_autoplaced yes)
		(effects
			(font
				(size 1.27 1.27)
			)
			(justify left bottom)
		)
		(property "Netclass" "85Ohm-diff_PCIE"
			(at 38.7985 110.49 0)
			(effects
				(font
					(size 1.27 1.27)
				)
				(justify left)
			)
		)
		(property "Component Class" ""
			(at -102.87 27.94 0)
			(effects
				(font
					(size 1.27 1.27)
					(italic yes)
				)
			)
		)
	)
	(netclass_flag ""
		(length 2.54)
		(shape round)
		(at 204.47 168.91 0)
		(effects
			(font
				(size 1.27 1.27)
			)
			(justify left bottom)
		)
		(property "Netclass" "90Ohm-diff_USB_2.0"
			(at 202.946 166.37 0)
			(effects
				(font
					(size 1.27 1.27)
				)
				(justify right)
			)
		)
		(property "Component Class" ""
			(at 41.91 127 0)
			(effects
				(font
					(size 1.27 1.27)
					(italic yes)
				)
				(justify right)
			)
		)
	)
	(netclass_flag ""
		(length 2.54)
		(shape round)
		(at 196.85 101.6 0)
		(effects
			(font
				(size 1.27 1.27)
			)
			(justify left bottom)
		)
		(property "Netclass" "85Ohm-diff_PCIE"
			(at 195.834 99.06 0)
			(effects
				(font
					(size 1.27 1.27)
				)
				(justify right)
			)
		)
		(property "Component Class" ""
			(at -22.86 2.54 0)
			(effects
				(font
					(size 1.27 1.27)
					(italic yes)
				)
			)
		)
	)
	(symbol
		(lib_id "antmicroCapacitors0603:C_22u_16V_0603")
		(at 327.66 93.98 90)
		(unit 1)
		(exclude_from_sim no)
		(in_bom yes)
		(on_board yes)
		(dnp no)
		(fields_autoplaced yes)
		(property "Reference" "C198"
			(at 330.2 90.1636 90)
			(effects
				(font
					(size 1.27 1.27)
					(thickness 0.15)
				)
				(justify right)
			)
		)
		(property "Value" "C_22u_16V_0603"
			(at 337.82 73.66 0)
			(effects
				(font
					(size 1.27 1.27)
					(thickness 0.15)
				)
				(justify left bottom)
				(hide yes)
			)
		)
		(property "Footprint" "antmicro-footprints:C_0603_1608Metric_EIA"
			(at 340.36 73.66 0)
			(effects
				(font
					(size 1.27 1.27)
					(thickness 0.15)
				)
				(justify left bottom)
				(hide yes)
			)
		)
		(property "Datasheet" "https://product.samsungsem.com/mlcc/CL10A226MO7JZN.do"
			(at 342.9 73.66 0)
			(effects
				(font
					(size 1.27 1.27)
					(thickness 0.15)
				)
				(justify left bottom)
				(hide yes)
			)
		)
		(property "Description" "SMD Multilayer Ceramic Capacitor"
			(at 327.66 93.98 0)
			(effects
				(font
					(size 1.27 1.27)
				)
				(hide yes)
			)
		)
		(property "MPN" "CL10A226MO7JZNC"
			(at 345.44 73.66 0)
			(effects
				(font
					(size 1.27 1.27)
					(thickness 0.15)
				)
				(justify left bottom)
				(hide yes)
			)
		)
		(property "Manufacturer" "Samsung Electro-Mechanics"
			(at 347.98 73.66 0)
			(effects
				(font
					(size 1.27 1.27)
					(thickness 0.15)
				)
				(justify left bottom)
				(hide yes)
			)
		)
		(property "License" "Apache-2.0"
			(at 350.52 73.66 0)
			(effects
				(font
					(size 1.27 1.27)
					(thickness 0.15)
				)
				(justify left bottom)
				(hide yes)
			)
		)
		(property "Author" "Antmicro"
			(at 353.06 73.66 0)
			(effects
				(font
					(size 1.27 1.27)
					(thickness 0.15)
				)
				(justify left bottom)
				(hide yes)
			)
		)
		(property "Val" "22u"
			(at 330.2 92.7036 90)
			(effects
				(font
					(size 1.27 1.27)
					(thickness 0.15)
				)
				(justify right)
			)
		)
		(property "Voltage" "16V"
			(at 355.6 73.66 0)
			(effects
				(font
					(size 1.27 1.27)
				)
				(justify left bottom)
				(hide yes)
			)
		)
		(property "Dielectric" ""
			(at 358.14 73.66 0)
			(effects
				(font
					(size 1.27 1.27)
				)
				(justify left bottom)
				(hide yes)
			)
		)
		(pin "2"
		)
		(pin "1"
		)
		(instances
			(project "jetson-agx-thor-baseboard"
				(path ""
					(reference "C198")
					(unit 1)
				)
			)
		)
	)
	(symbol
		(lib_id "antmicropower:GND")
		(at 327.66 95.25 0)
		(unit 1)
		(exclude_from_sim no)
		(in_bom yes)
		(on_board yes)
		(dnp no)
		(property "Reference" "#PWR0381"
			(at 327.66 101.6 0)
			(effects
				(font
					(size 1.27 1.27)
				)
				(hide yes)
			)
		)
		(property "Value" "GND"
			(at 327.66 99.06 0)
			(effects
				(font
					(size 1.27 1.27)
				)
			)
		)
		(property "Footprint" ""
			(at 327.66 95.25 0)
			(effects
				(font
					(size 1.27 1.27)
				)
				(hide yes)
			)
		)
		(property "Datasheet" ""
			(at 327.66 95.25 0)
			(effects
				(font
					(size 1.27 1.27)
				)
				(hide yes)
			)
		)
		(property "Description" ""
			(at 327.66 95.25 0)
			(effects
				(font
					(size 1.27 1.27)
				)
				(hide yes)
			)
		)
		(property "Author" "Antmicro"
			(at 336.55 102.87 0)
			(effects
				(font
					(size 1.27 1.27)
					(thickness 0.15)
				)
				(justify left bottom)
				(hide yes)
			)
		)
		(property "License" "Apache-2.0"
			(at 336.55 105.41 0)
			(effects
				(font
					(size 1.27 1.27)
					(thickness 0.15)
				)
				(justify left bottom)
				(hide yes)
			)
		)
		(pin "1"
		)
		(instances
			(project "jetson-agx-thor-baseboard"
				(path ""
					(reference "#PWR0381")
					(unit 1)
				)
			)
		)
	)
	(symbol
		(lib_id "antmicropower:GND")
		(at 147.32 105.41 0)
		(unit 1)
		(exclude_from_sim no)
		(in_bom yes)
		(on_board yes)
		(dnp no)
		(property "Reference" "#PWR0369"
			(at 147.32 111.76 0)
			(effects
				(font
					(size 1.27 1.27)
				)
				(justify left bottom)
				(hide yes)
			)
		)
		(property "Value" "GND"
			(at 145.415 109.855 0)
			(effects
				(font
					(size 1.27 1.27)
					(thickness 0.15)
				)
				(justify left bottom)
			)
		)
		(property "Footprint" ""
			(at 156.21 113.03 0)
			(effects
				(font
					(size 1.27 1.27)
					(thickness 0.15)
				)
				(justify left bottom)
				(hide yes)
			)
		)
		(property "Datasheet" ""
			(at 156.21 118.11 0)
			(effects
				(font
					(size 1.27 1.27)
					(thickness 0.15)
				)
				(justify left bottom)
				(hide yes)
			)
		)
		(property "Description" ""
			(at 147.32 105.41 0)
			(effects
				(font
					(size 1.27 1.27)
				)
				(hide yes)
			)
		)
		(property "Author" "Antmicro"
			(at 156.21 113.03 0)
			(effects
				(font
					(size 1.27 1.27)
					(thickness 0.15)
				)
				(justify left bottom)
				(hide yes)
			)
		)
		(property "License" "Apache-2.0"
			(at 156.21 115.57 0)
			(effects
				(font
					(size 1.27 1.27)
					(thickness 0.15)
				)
				(justify left bottom)
				(hide yes)
			)
		)
		(pin "1"
		)
		(instances
			(project "jetson-agx-thor-baseboard"
				(path ""
					(reference "#PWR0369")
					(unit 1)
				)
			)
		)
	)
	(symbol
		(lib_id "antmicroOscillators:Oscillator_32.768kHz_ECS_2520MV")
		(at 101.6 262.89 0)
		(unit 1)
		(exclude_from_sim no)
		(in_bom yes)
		(on_board yes)
		(dnp no)
		(fields_autoplaced yes)
		(property "Reference" "Y3"
			(at 111.125 252.73 0)
			(effects
				(font
					(size 1.27 1.27)
					(thickness 0.15)
				)
			)
		)
		(property "Value" "Oscillator_32.768kHz_ECS_2520MV"
			(at 127.635 275.59 0)
			(effects
				(font
					(size 1.27 1.27)
					(thickness 0.15)
				)
				(justify left bottom)
				(hide yes)
			)
		)
		(property "Footprint" "antmicro-footprints:Oscillator_SMD_ECS_2520MV_2.5x2mm"
			(at 127.635 278.13 0)
			(effects
				(font
					(size 1.27 1.27)
					(thickness 0.15)
				)
				(justify left bottom)
				(hide yes)
			)
		)
		(property "Datasheet" "https://ecsxtal.com/store/pdf/ECS-327MVATX.pdf"
			(at 127.635 280.67 0)
			(effects
				(font
					(size 1.27 1.27)
					(thickness 0.15)
				)
				(justify left bottom)
				(hide yes)
			)
		)
		(property "Description" "32.768 kHz XO (Standard) CMOS Oscillator 1.6V ~ 3.6V Enable/Disable 4-SMD, No Lead"
			(at 101.6 262.89 0)
			(effects
				(font
					(size 1.27 1.27)
				)
				(hide yes)
			)
		)
		(property "Manufacturer" "ECS Inc. International"
			(at 127.635 270.51 0)
			(effects
				(font
					(size 1.27 1.27)
					(thickness 0.15)
				)
				(justify left bottom)
				(hide yes)
			)
		)
		(property "MPN" "ECS-327MVATX-2-CN-TR3"
			(at 111.125 255.27 0)
			(effects
				(font
					(size 1.27 1.27)
					(thickness 0.15)
				)
			)
		)
		(property "Val" "32.768 kHz"
			(at 111.125 257.81 0)
			(effects
				(font
					(size 1.27 1.27)
					(thickness 0.15)
				)
			)
		)
		(property "Author" "Antmicro"
			(at 127.635 283.21 0)
			(effects
				(font
					(size 1.27 1.27)
					(thickness 0.15)
				)
				(justify left bottom)
				(hide yes)
			)
		)
		(property "License" "Apache-2.0"
			(at 127.635 285.75 0)
			(effects
				(font
					(size 1.27 1.27)
					(thickness 0.15)
				)
				(justify left bottom)
				(hide yes)
			)
		)
		(pin "2"
		)
		(pin "1"
		)
		(pin "4"
		)
		(pin "3"
		)
		(instances
			(project "jetson-agx-thor-baseboard"
				(path ""
					(reference "Y3")
					(unit 1)
				)
			)
		)
	)
	(symbol
		(lib_id "antmicroResistors0402:R_47k_0402")
		(at 246.38 92.71 90)
		(unit 1)
		(exclude_from_sim no)
		(in_bom yes)
		(on_board yes)
		(dnp no)
		(property "Reference" "R203"
			(at 247.65 88.9 90)
			(effects
				(font
					(size 1.27 1.27)
					(thickness 0.15)
				)
				(justify right)
			)
		)
		(property "Value" "R_47k_0402"
			(at 259.08 72.39 0)
			(effects
				(font
					(size 1.27 1.27)
					(thickness 0.15)
				)
				(justify left bottom)
				(hide yes)
			)
		)
		(property "Footprint" "antmicro-footprints:R_0402_1005Metric"
			(at 261.62 72.39 0)
			(effects
				(font
					(size 1.27 1.27)
					(thickness 0.15)
				)
				(justify left bottom)
				(hide yes)
			)
		)
		(property "Datasheet" "https://www.bourns.com/docs/product-datasheets/cr.pdf"
			(at 264.16 72.39 0)
			(effects
				(font
					(size 1.27 1.27)
					(thickness 0.15)
				)
				(justify left bottom)
				(hide yes)
			)
		)
		(property "Description" "SMD Chip Resistor, 47 kohm, ± 1%, 62.5 mW, 0402 [1005 Metric], Thick Film, General Purpose"
			(at 276.86 72.39 0)
			(effects
				(font
					(size 1.27 1.27)
				)
				(justify left bottom)
				(hide yes)
			)
		)
		(property "MPN" "CR0402-FX-4702GLF"
			(at 266.7 72.39 0)
			(effects
				(font
					(size 1.27 1.27)
					(thickness 0.15)
				)
				(justify left bottom)
				(hide yes)
			)
		)
		(property "Manufacturer" "Bourns"
			(at 269.24 72.39 0)
			(effects
				(font
					(size 1.27 1.27)
					(thickness 0.15)
				)
				(justify left bottom)
				(hide yes)
			)
		)
		(property "License" "Apache-2.0"
			(at 271.78 72.39 0)
			(effects
				(font
					(size 1.27 1.27)
					(thickness 0.15)
				)
				(justify left bottom)
				(hide yes)
			)
		)
		(property "Author" "Antmicro"
			(at 274.32 72.39 0)
			(effects
				(font
					(size 1.27 1.27)
					(thickness 0.15)
				)
				(justify left bottom)
				(hide yes)
			)
		)
		(property "Val" "47k"
			(at 247.65 91.44 90)
			(effects
				(font
					(size 1.27 1.27)
					(thickness 0.15)
				)
				(justify right)
			)
		)
		(property "Tolerance" "1%"
			(at 256.54 72.39 0)
			(effects
				(font
					(size 1.27 1.27)
				)
				(justify left bottom)
				(hide yes)
			)
		)
		(pin "2"
		)
		(pin "1"
		)
		(instances
			(project ""
				(path ""
					(reference "R203")
					(unit 1)
				)
			)
		)
	)
	(symbol
		(lib_id "antmicroPciConnectors:Bus_M.2_2199230-2")
		(at 262.89 93.98 0)
		(unit 1)
		(exclude_from_sim no)
		(in_bom yes)
		(on_board yes)
		(dnp no)
		(fields_autoplaced yes)
		(property "Reference" "J14"
			(at 278.13 86.36 0)
			(effects
				(font
					(size 1.27 1.27)
					(thickness 0.15)
				)
			)
		)
		(property "Value" "Bus_M.2_2199230-2"
			(at 278.13 87.63 0)
			(effects
				(font
					(size 1.27 1.27)
					(thickness 0.15)
				)
				(hide yes)
			)
		)
		(property "Footprint" "antmicro-footprints:Bus_M.2_Socket_Key_E_TE_2199230-6"
			(at 308.61 100.33 0)
			(effects
				(font
					(size 1.27 1.27)
					(thickness 0.15)
				)
				(justify left bottom)
				(hide yes)
			)
		)
		(property "Datasheet" "https://eu.mouser.com/datasheet/2/418/9/ENG_DS_1_1773702_1NGFFQRG_EN_0214_1_1773702_1NGFF_-3328593.pdf"
			(at 308.61 102.87 0)
			(effects
				(font
					(size 1.27 1.27)
					(thickness 0.15)
				)
				(justify left bottom)
				(hide yes)
			)
		)
		(property "Description" "Key E, PCI connector"
			(at 262.89 93.98 0)
			(effects
				(font
					(size 1.27 1.27)
				)
				(hide yes)
			)
		)
		(property "MPN" "2199230-2"
			(at 278.13 88.9 0)
			(effects
				(font
					(size 1.27 1.27)
					(thickness 0.15)
				)
			)
		)
		(property "Manufacturer" "TE Connectivity"
			(at 308.61 107.95 0)
			(effects
				(font
					(size 1.27 1.27)
					(thickness 0.15)
				)
				(justify left bottom)
				(hide yes)
			)
		)
		(property "Author" "Antmicro"
			(at 308.61 110.49 0)
			(effects
				(font
					(size 1.27 1.27)
					(thickness 0.15)
				)
				(justify left bottom)
				(hide yes)
			)
		)
		(property "License" "Apache-2.0"
			(at 308.61 113.03 0)
			(effects
				(font
					(size 1.27 1.27)
					(thickness 0.15)
				)
				(justify left bottom)
				(hide yes)
			)
		)
		(pin "50"
		)
		(pin "58"
		)
		(pin "70"
		)
		(pin "40"
		)
		(pin "39"
		)
		(pin "18"
		)
		(pin "57"
		)
		(pin "52"
		)
		(pin "34"
		)
		(pin "33"
		)
		(pin "12"
		)
		(pin "11"
		)
		(pin "10"
		)
		(pin "1"
		)
		(pin "74"
		)
		(pin "6"
		)
		(pin "16"
		)
		(pin "62"
		)
		(pin "66"
		)
		(pin "4"
		)
		(pin "15"
		)
		(pin "61"
		)
		(pin "3"
		)
		(pin "9"
		)
		(pin "20"
		)
		(pin "45"
		)
		(pin "60"
		)
		(pin "46"
		)
		(pin "36"
		)
		(pin "73"
		)
		(pin "14"
		)
		(pin "19"
		)
		(pin "72"
		)
		(pin "32"
		)
		(pin "22"
		)
		(pin "49"
		)
		(pin "75"
		)
		(pin "13"
		)
		(pin "51"
		)
		(pin "21"
		)
		(pin "71"
		)
		(pin "48"
		)
		(pin "68"
		)
		(pin "17"
		)
		(pin "23"
		)
		(pin "2"
		)
		(pin "53"
		)
		(pin "59"
		)
		(pin "38"
		)
		(pin "35"
		)
		(pin "7"
		)
		(pin "55"
		)
		(pin "5"
		)
		(pin "56"
		)
		(pin "41"
		)
		(pin "43"
		)
		(pin "42"
		)
		(pin "44"
		)
		(pin "8"
		)
		(pin "MP"
		)
		(pin "64"
		)
		(pin "69"
		)
		(pin "65"
		)
		(pin "47"
		)
		(pin "54"
		)
		(pin "37"
		)
		(pin "67"
		)
		(pin "63"
		)
		(instances
			(project "jetson-agx-thor-baseboard"
				(path ""
					(reference "J14")
					(unit 1)
				)
			)
		)
	)
	(symbol
		(lib_id "antmicroCapacitors0402:C_220n_0402")
		(at 64.77 127 0)
		(unit 1)
		(exclude_from_sim no)
		(in_bom yes)
		(on_board yes)
		(dnp no)
		(property "Reference" "C185"
			(at 64.008 125.73 0)
			(effects
				(font
					(size 1.27 1.27)
					(thickness 0.15)
				)
			)
		)
		(property "Value" "C_220n_0402"
			(at 80.01 149.86 0)
			(effects
				(font
					(size 1.27 1.27)
					(thickness 0.15)
				)
				(justify left bottom)
				(hide yes)
			)
		)
		(property "Footprint" "antmicro-footprints:C_0402_1005Metric"
			(at 80.01 152.4 0)
			(effects
				(font
					(size 1.27 1.27)
					(thickness 0.15)
				)
				(justify left bottom)
				(hide yes)
			)
		)
		(property "Datasheet" "https://www.yageo.com/en/Chart/Download/pdf/CC0402KRX5R6BB224"
			(at 80.01 154.94 0)
			(effects
				(font
					(size 1.27 1.27)
					(thickness 0.15)
				)
				(justify left bottom)
				(hide yes)
			)
		)
		(property "Description" "SMD Multilayer Ceramic Capacitor, 0.22 µF, 10 V, 0402 [1005 Metric], ± 10%, X5R, CC Series"
			(at 64.77 127 0)
			(effects
				(font
					(size 1.27 1.27)
				)
				(hide yes)
			)
		)
		(property "MPN" "CC0402KRX5R6BB224"
			(at 80.01 157.48 0)
			(effects
				(font
					(size 1.27 1.27)
					(thickness 0.15)
				)
				(justify left bottom)
				(hide yes)
			)
		)
		(property "Val" "220n"
			(at 71.12 125.73 0)
			(effects
				(font
					(size 1.27 1.27)
					(thickness 0.15)
				)
			)
		)
		(property "Voltage" "25V"
			(at 80.01 137.16 0)
			(effects
				(font
					(size 1.27 1.27)
					(thickness 0.15)
				)
				(justify left bottom)
				(hide yes)
			)
		)
		(property "Dielectric" "X7R"
			(at 80.01 139.7 0)
			(effects
				(font
					(size 1.27 1.27)
					(thickness 0.15)
				)
				(justify left bottom)
				(hide yes)
			)
		)
		(property "Manufacturer" "YAGEO"
			(at 80.01 142.24 0)
			(effects
				(font
					(size 1.27 1.27)
					(thickness 0.15)
				)
				(justify left bottom)
				(hide yes)
			)
		)
		(property "License" "Apache-2.0"
			(at 80.01 144.78 0)
			(effects
				(font
					(size 1.27 1.27)
					(thickness 0.15)
				)
				(justify left bottom)
				(hide yes)
			)
		)
		(property "Author" "Antmicro"
			(at 80.01 147.32 0)
			(effects
				(font
					(size 1.27 1.27)
					(thickness 0.15)
				)
				(justify left bottom)
				(hide yes)
			)
		)
		(property "Public" "False"
			(at 85.09 160.02 0)
			(effects
				(font
					(size 1.27 1.27)
				)
				(justify left bottom)
				(hide yes)
			)
		)
		(pin "2"
		)
		(pin "1"
		)
		(instances
			(project "jetson-agx-thor-baseboard"
				(path ""
					(reference "C185")
					(unit 1)
				)
			)
		)
	)
	(symbol
		(lib_id "antmicroResistors0402:R_200R_0402")
		(at 375.92 170.18 90)
		(unit 1)
		(exclude_from_sim no)
		(in_bom yes)
		(on_board yes)
		(dnp no)
		(fields_autoplaced yes)
		(property "Reference" "R222"
			(at 378.46 166.37 90)
			(effects
				(font
					(size 1.27 1.27)
				)
				(justify right)
			)
		)
		(property "Value" "R_200R_0402"
			(at 388.62 149.86 0)
			(effects
				(font
					(size 1.27 1.27)
					(thickness 0.15)
				)
				(justify left bottom)
				(hide yes)
			)
		)
		(property "Footprint" "antmicro-footprints:R_0402_1005Metric"
			(at 391.16 149.86 0)
			(effects
				(font
					(size 1.27 1.27)
					(thickness 0.15)
				)
				(justify left bottom)
				(hide yes)
			)
		)
		(property "Datasheet" "https://www.bourns.com/docs/product-datasheets/cr.pdf"
			(at 393.7 149.86 0)
			(effects
				(font
					(size 1.27 1.27)
					(thickness 0.15)
				)
				(justify left bottom)
				(hide yes)
			)
		)
		(property "Description" "SMD Chip Resistor, 200 ohm, ± 1%, 62.5 mW, 0402 [1005 Metric], Thick Film, General Purpose"
			(at 375.92 170.18 0)
			(effects
				(font
					(size 1.27 1.27)
				)
				(hide yes)
			)
		)
		(property "Manufacturer" "Bourns"
			(at 398.78 149.86 0)
			(effects
				(font
					(size 1.27 1.27)
					(thickness 0.15)
				)
				(justify left bottom)
				(hide yes)
			)
		)
		(property "MPN" "CR0402-FX-2000GLF"
			(at 396.24 149.86 0)
			(effects
				(font
					(size 1.27 1.27)
					(thickness 0.15)
				)
				(justify left bottom)
				(hide yes)
			)
		)
		(property "Val" "200R"
			(at 378.46 168.91 90)
			(effects
				(font
					(size 1.27 1.27)
					(thickness 0.15)
				)
				(justify right)
			)
		)
		(property "License" "Apache-2.0"
			(at 401.32 149.86 0)
			(effects
				(font
					(size 1.27 1.27)
					(thickness 0.15)
				)
				(justify left bottom)
				(hide yes)
			)
		)
		(property "Author" "Antmicro"
			(at 403.86 149.86 0)
			(effects
				(font
					(size 1.27 1.27)
					(thickness 0.15)
				)
				(justify left bottom)
				(hide yes)
			)
		)
		(property "Tolerance" "1%"
			(at 386.08 149.86 0)
			(effects
				(font
					(size 1.27 1.27)
				)
				(justify left bottom)
				(hide yes)
			)
		)
		(pin "1"
		)
		(pin "2"
		)
		(instances
			(project "jetson-agx-thor-baseboard"
				(path ""
					(reference "R222")
					(unit 1)
				)
			)
		)
	)
	(symbol
		(lib_id "antmicropower:GND")
		(at 318.77 95.25 0)
		(unit 1)
		(exclude_from_sim no)
		(in_bom yes)
		(on_board yes)
		(dnp no)
		(property "Reference" "#PWR0379"
			(at 318.77 101.6 0)
			(effects
				(font
					(size 1.27 1.27)
				)
				(hide yes)
			)
		)
		(property "Value" "GND"
			(at 318.77 99.06 0)
			(effects
				(font
					(size 1.27 1.27)
				)
			)
		)
		(property "Footprint" ""
			(at 318.77 95.25 0)
			(effects
				(font
					(size 1.27 1.27)
				)
				(hide yes)
			)
		)
		(property "Datasheet" ""
			(at 318.77 95.25 0)
			(effects
				(font
					(size 1.27 1.27)
				)
				(hide yes)
			)
		)
		(property "Description" ""
			(at 318.77 95.25 0)
			(effects
				(font
					(size 1.27 1.27)
				)
				(hide yes)
			)
		)
		(property "Author" "Antmicro"
			(at 327.66 102.87 0)
			(effects
				(font
					(size 1.27 1.27)
					(thickness 0.15)
				)
				(justify left bottom)
				(hide yes)
			)
		)
		(property "License" "Apache-2.0"
			(at 327.66 105.41 0)
			(effects
				(font
					(size 1.27 1.27)
					(thickness 0.15)
				)
				(justify left bottom)
				(hide yes)
			)
		)
		(pin "1"
		)
		(instances
			(project "jetson-agx-thor-baseboard"
				(path ""
					(reference "#PWR0379")
					(unit 1)
				)
			)
		)
	)
	(symbol
		(lib_id "antmicroResistors0402:R_200R_0402")
		(at 132.08 147.32 90)
		(unit 1)
		(exclude_from_sim no)
		(in_bom yes)
		(on_board yes)
		(dnp no)
		(fields_autoplaced yes)
		(property "Reference" "R211"
			(at 134.62 143.51 90)
			(effects
				(font
					(size 1.27 1.27)
				)
				(justify right)
			)
		)
		(property "Value" "R_200R_0402"
			(at 144.78 127 0)
			(effects
				(font
					(size 1.27 1.27)
					(thickness 0.15)
				)
				(justify left bottom)
				(hide yes)
			)
		)
		(property "Footprint" "antmicro-footprints:R_0402_1005Metric"
			(at 147.32 127 0)
			(effects
				(font
					(size 1.27 1.27)
					(thickness 0.15)
				)
				(justify left bottom)
				(hide yes)
			)
		)
		(property "Datasheet" "https://www.bourns.com/docs/product-datasheets/cr.pdf"
			(at 149.86 127 0)
			(effects
				(font
					(size 1.27 1.27)
					(thickness 0.15)
				)
				(justify left bottom)
				(hide yes)
			)
		)
		(property "Description" "SMD Chip Resistor, 200 ohm, ± 1%, 62.5 mW, 0402 [1005 Metric], Thick Film, General Purpose"
			(at 132.08 147.32 0)
			(effects
				(font
					(size 1.27 1.27)
				)
				(hide yes)
			)
		)
		(property "Manufacturer" "Bourns"
			(at 154.94 127 0)
			(effects
				(font
					(size 1.27 1.27)
					(thickness 0.15)
				)
				(justify left bottom)
				(hide yes)
			)
		)
		(property "MPN" "CR0402-FX-2000GLF"
			(at 152.4 127 0)
			(effects
				(font
					(size 1.27 1.27)
					(thickness 0.15)
				)
				(justify left bottom)
				(hide yes)
			)
		)
		(property "Val" "200R"
			(at 134.62 146.05 90)
			(effects
				(font
					(size 1.27 1.27)
					(thickness 0.15)
				)
				(justify right)
			)
		)
		(property "License" "Apache-2.0"
			(at 157.48 127 0)
			(effects
				(font
					(size 1.27 1.27)
					(thickness 0.15)
				)
				(justify left bottom)
				(hide yes)
			)
		)
		(property "Author" "Antmicro"
			(at 160.02 127 0)
			(effects
				(font
					(size 1.27 1.27)
					(thickness 0.15)
				)
				(justify left bottom)
				(hide yes)
			)
		)
		(property "Tolerance" "1%"
			(at 142.24 127 0)
			(effects
				(font
					(size 1.27 1.27)
				)
				(justify left bottom)
				(hide yes)
			)
		)
		(pin "1"
		)
		(pin "2"
		)
		(instances
			(project "jetson-agx-thor-baseboard"
				(path ""
					(reference "R211")
					(unit 1)
				)
			)
		)
	)
	(symbol
		(lib_id "antmicroPciConnectors:Bus_M.2_1-2199230-6")
		(at 100.33 102.87 0)
		(unit 1)
		(exclude_from_sim no)
		(in_bom yes)
		(on_board yes)
		(dnp no)
		(fields_autoplaced yes)
		(property "Reference" "J13"
			(at 115.57 95.25 0)
			(effects
				(font
					(size 1.27 1.27)
					(thickness 0.15)
				)
			)
		)
		(property "Value" "Bus_M.2_1-2199230-6"
			(at 146.05 110.49 0)
			(effects
				(font
					(size 1.27 1.27)
					(thickness 0.15)
				)
				(justify left bottom)
				(hide yes)
			)
		)
		(property "Footprint" "antmicro-footprints:Bus_M.2_Socket_Key_M_TE_1-2199230-6"
			(at 146.05 113.03 0)
			(effects
				(font
					(size 1.27 1.27)
					(thickness 0.15)
				)
				(justify left bottom)
				(hide yes)
			)
		)
		(property "Datasheet" "https://www.te.com/commerce/DocumentDelivery/DDEController?Action=srchrtrv&DocNm=2199230&DocType=Customer+Drawing&DocLang=English"
			(at 146.05 115.57 0)
			(effects
				(font
					(size 1.27 1.27)
					(thickness 0.15)
				)
				(justify left bottom)
				(hide yes)
			)
		)
		(property "Description" "Key M Card Edge Connector, 0, Dual Side, 67 Contacts, Surface Mount, Right Angle, Solder"
			(at 100.33 102.87 0)
			(effects
				(font
					(size 1.27 1.27)
				)
				(hide yes)
			)
		)
		(property "Manufacturer" "TE Connectivity"
			(at 146.05 118.11 0)
			(effects
				(font
					(size 1.27 1.27)
					(thickness 0.15)
				)
				(justify left bottom)
				(hide yes)
			)
		)
		(property "MPN" "1-2199230-6"
			(at 115.57 97.79 0)
			(effects
				(font
					(size 1.27 1.27)
					(thickness 0.15)
				)
			)
		)
		(property "Author" "Antmicro"
			(at 146.05 120.65 0)
			(effects
				(font
					(size 1.27 1.27)
					(thickness 0.15)
				)
				(justify left bottom)
				(hide yes)
			)
		)
		(property "License" "Apache-2.0"
			(at 146.05 123.19 0)
			(effects
				(font
					(size 1.27 1.27)
					(thickness 0.15)
				)
				(justify left bottom)
				(hide yes)
			)
		)
		(pin "1"
		)
		(pin "10"
		)
		(pin "11"
		)
		(pin "12"
		)
		(pin "13"
		)
		(pin "14"
		)
		(pin "15"
		)
		(pin "16"
		)
		(pin "17"
		)
		(pin "18"
		)
		(pin "19"
		)
		(pin "2"
		)
		(pin "20"
		)
		(pin "21"
		)
		(pin "22"
		)
		(pin "23"
		)
		(pin "24"
		)
		(pin "25"
		)
		(pin "26"
		)
		(pin "27"
		)
		(pin "28"
		)
		(pin "29"
		)
		(pin "3"
		)
		(pin "30"
		)
		(pin "31"
		)
		(pin "32"
		)
		(pin "33"
		)
		(pin "34"
		)
		(pin "35"
		)
		(pin "36"
		)
		(pin "37"
		)
		(pin "38"
		)
		(pin "39"
		)
		(pin "4"
		)
		(pin "40"
		)
		(pin "41"
		)
		(pin "42"
		)
		(pin "43"
		)
		(pin "44"
		)
		(pin "45"
		)
		(pin "46"
		)
		(pin "47"
		)
		(pin "48"
		)
		(pin "49"
		)
		(pin "5"
		)
		(pin "50"
		)
		(pin "51"
		)
		(pin "52"
		)
		(pin "53"
		)
		(pin "54"
		)
		(pin "55"
		)
		(pin "56"
		)
		(pin "57"
		)
		(pin "58"
		)
		(pin "6"
		)
		(pin "67"
		)
		(pin "68"
		)
		(pin "69"
		)
		(pin "7"
		)
		(pin "70"
		)
		(pin "71"
		)
		(pin "72"
		)
		(pin "73"
		)
		(pin "74"
		)
		(pin "75"
		)
		(pin "8"
		)
		(pin "9"
		)
		(pin "MP1"
		)
		(pin "MP2"
		)
		(instances
			(project "jetson-agx-thor-baseboard"
				(path ""
					(reference "J13")
					(unit 1)
				)
			)
		)
	)
	(symbol
		(lib_id "antmicropower:GND")
		(at 132.08 181.61 0)
		(unit 1)
		(exclude_from_sim no)
		(in_bom yes)
		(on_board yes)
		(dnp no)
		(property "Reference" "#PWR0367"
			(at 132.08 187.96 0)
			(effects
				(font
					(size 1.27 1.27)
				)
				(justify left bottom)
				(hide yes)
			)
		)
		(property "Value" "GND"
			(at 130.175 186.055 0)
			(effects
				(font
					(size 1.27 1.27)
					(thickness 0.15)
				)
				(justify left bottom)
			)
		)
		(property "Footprint" ""
			(at 140.97 189.23 0)
			(effects
				(font
					(size 1.27 1.27)
					(thickness 0.15)
				)
				(justify left bottom)
				(hide yes)
			)
		)
		(property "Datasheet" ""
			(at 140.97 194.31 0)
			(effects
				(font
					(size 1.27 1.27)
					(thickness 0.15)
				)
				(justify left bottom)
				(hide yes)
			)
		)
		(property "Description" ""
			(at 132.08 181.61 0)
			(effects
				(font
					(size 1.27 1.27)
				)
				(hide yes)
			)
		)
		(property "Author" "Antmicro"
			(at 140.97 189.23 0)
			(effects
				(font
					(size 1.27 1.27)
					(thickness 0.15)
				)
				(justify left bottom)
				(hide yes)
			)
		)
		(property "License" "Apache-2.0"
			(at 140.97 191.77 0)
			(effects
				(font
					(size 1.27 1.27)
					(thickness 0.15)
				)
				(justify left bottom)
				(hide yes)
			)
		)
		(pin "1"
		)
		(instances
			(project "jetson-agx-thor-baseboard"
				(path ""
					(reference "#PWR0367")
					(unit 1)
				)
			)
		)
	)
	(symbol
		(lib_id "antmicroResistors0402:R_47k_0402")
		(at 83.82 96.52 90)
		(mirror x)
		(unit 1)
		(exclude_from_sim no)
		(in_bom no)
		(on_board yes)
		(dnp yes)
		(property "Reference" "R209"
			(at 85.09 97.79 90)
			(effects
				(font
					(size 1.27 1.27)
				)
				(justify right)
			)
		)
		(property "Value" "R_47k_0402"
			(at 96.52 116.84 0)
			(effects
				(font
					(size 1.27 1.27)
					(thickness 0.15)
				)
				(justify left bottom)
				(hide yes)
			)
		)
		(property "Footprint" "antmicro-footprints:R_0402_1005Metric"
			(at 99.06 116.84 0)
			(effects
				(font
					(size 1.27 1.27)
					(thickness 0.15)
				)
				(justify left bottom)
				(hide yes)
			)
		)
		(property "Datasheet" "https://www.bourns.com/docs/product-datasheets/cr.pdf"
			(at 101.6 116.84 0)
			(effects
				(font
					(size 1.27 1.27)
					(thickness 0.15)
				)
				(justify left bottom)
				(hide yes)
			)
		)
		(property "Description" "SMD Chip Resistor, 47 kohm, ± 1%, 62.5 mW, 0402 [1005 Metric], Thick Film, General Purpose"
			(at 83.82 96.52 0)
			(effects
				(font
					(size 1.27 1.27)
				)
				(hide yes)
			)
		)
		(property "Manufacturer" "Bourns"
			(at 106.68 116.84 0)
			(effects
				(font
					(size 1.27 1.27)
					(thickness 0.15)
				)
				(justify left bottom)
				(hide yes)
			)
		)
		(property "MPN" "CR0402-FX-4702GLF"
			(at 104.14 116.84 0)
			(effects
				(font
					(size 1.27 1.27)
					(thickness 0.15)
				)
				(justify left bottom)
				(hide yes)
			)
		)
		(property "Val" "47k"
			(at 85.09 100.33 90)
			(effects
				(font
					(size 1.27 1.27)
					(thickness 0.15)
				)
				(justify right)
			)
		)
		(property "License" "Apache-2.0"
			(at 109.22 116.84 0)
			(effects
				(font
					(size 1.27 1.27)
					(thickness 0.15)
				)
				(justify left bottom)
				(hide yes)
			)
		)
		(property "Author" "Antmicro"
			(at 111.76 116.84 0)
			(effects
				(font
					(size 1.27 1.27)
					(thickness 0.15)
				)
				(justify left bottom)
				(hide yes)
			)
		)
		(property "Tolerance" "1%"
			(at 93.98 116.84 0)
			(effects
				(font
					(size 1.27 1.27)
				)
				(justify left bottom)
				(hide yes)
			)
		)
		(pin "1"
		)
		(pin "2"
		)
		(instances
			(project "jetson-agx-thor-baseboard"
				(path ""
					(reference "R209")
					(unit 1)
				)
			)
		)
	)
	(symbol
		(lib_id "antmicroTestPoints:TP_0.75mm_SMD")
		(at 147.32 134.62 0)
		(unit 1)
		(exclude_from_sim no)
		(in_bom no)
		(on_board yes)
		(dnp no)
		(property "Reference" "TP38"
			(at 151.13 134.62 0)
			(effects
				(font
					(size 1.27 1.27)
				)
				(justify left)
			)
		)
		(property "Value" "TP_0.75mm_SMD"
			(at 157.48 138.43 0)
			(effects
				(font
					(size 1.27 1.27)
					(thickness 0.15)
				)
				(justify left bottom)
				(hide yes)
			)
		)
		(property "Footprint" "antmicro-footprints:TP_SMD_0.75mm"
			(at 157.48 140.97 0)
			(effects
				(font
					(size 1.27 1.27)
					(thickness 0.15)
				)
				(justify left bottom)
				(hide yes)
			)
		)
		(property "Datasheet" ""
			(at 165.1 147.32 0)
			(effects
				(font
					(size 1.27 1.27)
					(thickness 0.15)
				)
				(justify left bottom)
				(hide yes)
			)
		)
		(property "Description" "SMT test point"
			(at 147.32 134.62 0)
			(effects
				(font
					(size 1.27 1.27)
				)
				(hide yes)
			)
		)
		(property "MPN" ""
			(at 158.115 146.05 0)
			(effects
				(font
					(size 1.27 1.27)
					(thickness 0.15)
				)
				(justify left bottom)
				(hide yes)
			)
		)
		(property "Manufacturer" ""
			(at 158.115 140.97 0)
			(effects
				(font
					(size 1.27 1.27)
					(thickness 0.15)
				)
				(justify left bottom)
				(hide yes)
			)
		)
		(property "Author" "Antmicro"
			(at 157.48 143.51 0)
			(effects
				(font
					(size 1.27 1.27)
					(thickness 0.15)
				)
				(justify left bottom)
				(hide yes)
			)
		)
		(property "License" "Apache-2.0"
			(at 157.48 146.05 0)
			(effects
				(font
					(size 1.27 1.27)
					(thickness 0.15)
				)
				(justify left bottom)
				(hide yes)
			)
		)
		(pin "1"
		)
		(instances
			(project "jetson-agx-thor-baseboard"
				(path ""
					(reference "TP38")
					(unit 1)
				)
			)
		)
	)
	(symbol
		(lib_id "antmicropower:GND")
		(at 97.79 215.9 0)
		(unit 1)
		(exclude_from_sim no)
		(in_bom yes)
		(on_board yes)
		(dnp no)
		(property "Reference" "#PWR0365"
			(at 106.68 218.44 0)
			(effects
				(font
					(size 1.27 1.27)
					(thickness 0.15)
				)
				(justify left bottom)
				(hide yes)
			)
		)
		(property "Value" "GND"
			(at 97.79 219.71 0)
			(effects
				(font
					(size 1.27 1.27)
					(thickness 0.15)
				)
			)
		)
		(property "Footprint" ""
			(at 106.68 223.52 0)
			(effects
				(font
					(size 1.27 1.27)
					(thickness 0.15)
				)
				(justify left bottom)
				(hide yes)
			)
		)
		(property "Datasheet" ""
			(at 106.68 228.6 0)
			(effects
				(font
					(size 1.27 1.27)
					(thickness 0.15)
				)
				(justify left bottom)
				(hide yes)
			)
		)
		(property "Description" ""
			(at 97.79 215.9 0)
			(effects
				(font
					(size 1.27 1.27)
				)
				(hide yes)
			)
		)
		(property "Author" "Antmicro"
			(at 106.68 223.52 0)
			(effects
				(font
					(size 1.27 1.27)
					(thickness 0.15)
				)
				(justify left bottom)
				(hide yes)
			)
		)
		(property "License" "Apache-2.0"
			(at 106.68 226.06 0)
			(effects
				(font
					(size 1.27 1.27)
					(thickness 0.15)
				)
				(justify left bottom)
				(hide yes)
			)
		)
		(pin "1"
		)
		(instances
			(project "jetson-agx-thor-baseboard"
				(path ""
					(reference "#PWR0365")
					(unit 1)
				)
			)
		)
	)
	(symbol
		(lib_id "antmicroCapacitors0402:C_220n_0402")
		(at 64.77 157.48 0)
		(unit 1)
		(exclude_from_sim no)
		(in_bom yes)
		(on_board yes)
		(dnp no)
		(property "Reference" "C187"
			(at 64.008 156.21 0)
			(effects
				(font
					(size 1.27 1.27)
					(thickness 0.15)
				)
			)
		)
		(property "Value" "C_220n_0402"
			(at 80.01 180.34 0)
			(effects
				(font
					(size 1.27 1.27)
					(thickness 0.15)
				)
				(justify left bottom)
				(hide yes)
			)
		)
		(property "Footprint" "antmicro-footprints:C_0402_1005Metric"
			(at 80.01 182.88 0)
			(effects
				(font
					(size 1.27 1.27)
					(thickness 0.15)
				)
				(justify left bottom)
				(hide yes)
			)
		)
		(property "Datasheet" "https://www.yageo.com/en/Chart/Download/pdf/CC0402KRX5R6BB224"
			(at 80.01 185.42 0)
			(effects
				(font
					(size 1.27 1.27)
					(thickness 0.15)
				)
				(justify left bottom)
				(hide yes)
			)
		)
		(property "Description" "SMD Multilayer Ceramic Capacitor, 0.22 µF, 10 V, 0402 [1005 Metric], ± 10%, X5R, CC Series"
			(at 64.77 157.48 0)
			(effects
				(font
					(size 1.27 1.27)
				)
				(hide yes)
			)
		)
		(property "MPN" "CC0402KRX5R6BB224"
			(at 80.01 187.96 0)
			(effects
				(font
					(size 1.27 1.27)
					(thickness 0.15)
				)
				(justify left bottom)
				(hide yes)
			)
		)
		(property "Val" "220n"
			(at 71.12 156.21 0)
			(effects
				(font
					(size 1.27 1.27)
					(thickness 0.15)
				)
			)
		)
		(property "Voltage" "25V"
			(at 80.01 167.64 0)
			(effects
				(font
					(size 1.27 1.27)
					(thickness 0.15)
				)
				(justify left bottom)
				(hide yes)
			)
		)
		(property "Dielectric" "X7R"
			(at 80.01 170.18 0)
			(effects
				(font
					(size 1.27 1.27)
					(thickness 0.15)
				)
				(justify left bottom)
				(hide yes)
			)
		)
		(property "Manufacturer" "YAGEO"
			(at 80.01 172.72 0)
			(effects
				(font
					(size 1.27 1.27)
					(thickness 0.15)
				)
				(justify left bottom)
				(hide yes)
			)
		)
		(property "License" "Apache-2.0"
			(at 80.01 175.26 0)
			(effects
				(font
					(size 1.27 1.27)
					(thickness 0.15)
				)
				(justify left bottom)
				(hide yes)
			)
		)
		(property "Author" "Antmicro"
			(at 80.01 177.8 0)
			(effects
				(font
					(size 1.27 1.27)
					(thickness 0.15)
				)
				(justify left bottom)
				(hide yes)
			)
		)
		(property "Public" "False"
			(at 85.09 190.5 0)
			(effects
				(font
					(size 1.27 1.27)
				)
				(justify left bottom)
				(hide yes)
			)
		)
		(pin "2"
		)
		(pin "1"
		)
		(instances
			(project "jetson-agx-thor-baseboard"
				(path ""
					(reference "C187")
					(unit 1)
				)
			)
		)
	)
	(symbol
		(lib_id "antmicroTestPoints:TP_0.75mm_SMD")
		(at 147.32 132.08 0)
		(unit 1)
		(exclude_from_sim no)
		(in_bom no)
		(on_board yes)
		(dnp no)
		(property "Reference" "TP37"
			(at 151.13 132.08 0)
			(effects
				(font
					(size 1.27 1.27)
				)
				(justify left)
			)
		)
		(property "Value" "TP_0.75mm_SMD"
			(at 157.48 135.89 0)
			(effects
				(font
					(size 1.27 1.27)
					(thickness 0.15)
				)
				(justify left bottom)
				(hide yes)
			)
		)
		(property "Footprint" "antmicro-footprints:TP_SMD_0.75mm"
			(at 157.48 138.43 0)
			(effects
				(font
					(size 1.27 1.27)
					(thickness 0.15)
				)
				(justify left bottom)
				(hide yes)
			)
		)
		(property "Datasheet" ""
			(at 165.1 144.78 0)
			(effects
				(font
					(size 1.27 1.27)
					(thickness 0.15)
				)
				(justify left bottom)
				(hide yes)
			)
		)
		(property "Description" "SMT test point"
			(at 147.32 132.08 0)
			(effects
				(font
					(size 1.27 1.27)
				)
				(hide yes)
			)
		)
		(property "MPN" ""
			(at 158.115 143.51 0)
			(effects
				(font
					(size 1.27 1.27)
					(thickness 0.15)
				)
				(justify left bottom)
				(hide yes)
			)
		)
		(property "Manufacturer" ""
			(at 158.115 138.43 0)
			(effects
				(font
					(size 1.27 1.27)
					(thickness 0.15)
				)
				(justify left bottom)
				(hide yes)
			)
		)
		(property "Author" "Antmicro"
			(at 157.48 140.97 0)
			(effects
				(font
					(size 1.27 1.27)
					(thickness 0.15)
				)
				(justify left bottom)
				(hide yes)
			)
		)
		(property "License" "Apache-2.0"
			(at 157.48 143.51 0)
			(effects
				(font
					(size 1.27 1.27)
					(thickness 0.15)
				)
				(justify left bottom)
				(hide yes)
			)
		)
		(pin "1"
		)
		(instances
			(project "jetson-agx-thor-baseboard"
				(path ""
					(reference "TP37")
					(unit 1)
				)
			)
		)
	)
	(symbol
		(lib_id "antmicroCapacitors0402:C_220n_0402")
		(at 64.77 172.72 0)
		(unit 1)
		(exclude_from_sim no)
		(in_bom yes)
		(on_board yes)
		(dnp no)
		(property "Reference" "C188"
			(at 64.008 171.45 0)
			(effects
				(font
					(size 1.27 1.27)
					(thickness 0.15)
				)
			)
		)
		(property "Value" "C_220n_0402"
			(at 80.01 195.58 0)
			(effects
				(font
					(size 1.27 1.27)
					(thickness 0.15)
				)
				(justify left bottom)
				(hide yes)
			)
		)
		(property "Footprint" "antmicro-footprints:C_0402_1005Metric"
			(at 80.01 198.12 0)
			(effects
				(font
					(size 1.27 1.27)
					(thickness 0.15)
				)
				(justify left bottom)
				(hide yes)
			)
		)
		(property "Datasheet" "https://www.yageo.com/en/Chart/Download/pdf/CC0402KRX5R6BB224"
			(at 80.01 200.66 0)
			(effects
				(font
					(size 1.27 1.27)
					(thickness 0.15)
				)
				(justify left bottom)
				(hide yes)
			)
		)
		(property "Description" "SMD Multilayer Ceramic Capacitor, 0.22 µF, 10 V, 0402 [1005 Metric], ± 10%, X5R, CC Series"
			(at 64.77 172.72 0)
			(effects
				(font
					(size 1.27 1.27)
				)
				(hide yes)
			)
		)
		(property "MPN" "CC0402KRX5R6BB224"
			(at 80.01 203.2 0)
			(effects
				(font
					(size 1.27 1.27)
					(thickness 0.15)
				)
				(justify left bottom)
				(hide yes)
			)
		)
		(property "Val" "220n"
			(at 71.12 171.45 0)
			(effects
				(font
					(size 1.27 1.27)
					(thickness 0.15)
				)
			)
		)
		(property "Voltage" "25V"
			(at 80.01 182.88 0)
			(effects
				(font
					(size 1.27 1.27)
					(thickness 0.15)
				)
				(justify left bottom)
				(hide yes)
			)
		)
		(property "Dielectric" "X7R"
			(at 80.01 185.42 0)
			(effects
				(font
					(size 1.27 1.27)
					(thickness 0.15)
				)
				(justify left bottom)
				(hide yes)
			)
		)
		(property "Manufacturer" "YAGEO"
			(at 80.01 187.96 0)
			(effects
				(font
					(size 1.27 1.27)
					(thickness 0.15)
				)
				(justify left bottom)
				(hide yes)
			)
		)
		(property "License" "Apache-2.0"
			(at 80.01 190.5 0)
			(effects
				(font
					(size 1.27 1.27)
					(thickness 0.15)
				)
				(justify left bottom)
				(hide yes)
			)
		)
		(property "Author" "Antmicro"
			(at 80.01 193.04 0)
			(effects
				(font
					(size 1.27 1.27)
					(thickness 0.15)
				)
				(justify left bottom)
				(hide yes)
			)
		)
		(property "Public" "False"
			(at 85.09 205.74 0)
			(effects
				(font
					(size 1.27 1.27)
				)
				(justify left bottom)
				(hide yes)
			)
		)
		(pin "2"
		)
		(pin "1"
		)
		(instances
			(project "jetson-agx-thor-baseboard"
				(path ""
					(reference "C188")
					(unit 1)
				)
			)
		)
	)
	(symbol
		(lib_id "antmicroMechanicalParts:Spacer_Drill3.7mm_H2.5mm_9774025151R")
		(at 284.48 234.95 180)
		(unit 1)
		(exclude_from_sim no)
		(in_bom yes)
		(on_board yes)
		(dnp no)
		(fields_autoplaced yes)
		(property "Reference" "H10"
			(at 279.4 227.965 0)
			(effects
				(font
					(size 1.27 1.27)
					(thickness 0.15)
				)
			)
		)
		(property "Value" "Spacer_Drill3.7mm_H2.5mm_9774025151R"
			(at 279.4 230.505 0)
			(effects
				(font
					(size 1.27 1.27)
					(thickness 0.15)
				)
			)
		)
		(property "Footprint" "antmicro-footprints:Spacer_Drill3.7mm_H2.5mm_9774025151R"
			(at 261.62 227.33 0)
			(effects
				(font
					(size 1.27 1.27)
					(thickness 0.15)
				)
				(justify left bottom)
				(hide yes)
			)
		)
		(property "Datasheet" "https://www.we-online.com/components/products/datasheet/9774025151R.pdf"
			(at 261.62 224.79 0)
			(effects
				(font
					(size 1.27 1.27)
					(thickness 0.15)
				)
				(justify left bottom)
				(hide yes)
			)
		)
		(property "Description" "Spacer, SMT, Non Stop, Steel, Swage Round, 5.1 mm x 2.5 mm, M2.5 Thread, WA-SMSI Series"
			(at 284.48 234.95 0)
			(effects
				(font
					(size 1.27 1.27)
				)
				(hide yes)
			)
		)
		(property "Manufacturer" "Würth Elektronik"
			(at 261.62 222.25 0)
			(effects
				(font
					(size 1.27 1.27)
					(thickness 0.15)
				)
				(justify left bottom)
				(hide yes)
			)
		)
		(property "MPN" "9774025151R"
			(at 261.62 219.71 0)
			(effects
				(font
					(size 1.27 1.27)
					(thickness 0.15)
				)
				(justify left bottom)
				(hide yes)
			)
		)
		(property "Author" "Antmicro"
			(at 261.62 217.17 0)
			(effects
				(font
					(size 1.27 1.27)
					(thickness 0.15)
				)
				(justify left bottom)
				(hide yes)
			)
		)
		(property "License" "Apache-2.0"
			(at 261.62 214.63 0)
			(effects
				(font
					(size 1.27 1.27)
					(thickness 0.15)
				)
				(justify left bottom)
				(hide yes)
			)
		)
		(pin "1"
		)
		(instances
			(project "jetson-agx-thor-baseboard"
				(path ""
					(reference "H10")
					(unit 1)
				)
			)
		)
	)
	(symbol
		(lib_id "antmicroMechanicalParts:Spacer_Drill3.7mm_H2.5mm_9774025151R")
		(at 96.52 214.63 0)
		(mirror y)
		(unit 1)
		(exclude_from_sim no)
		(in_bom yes)
		(on_board yes)
		(dnp no)
		(property "Reference" "H9"
			(at 87.63 213.36 0)
			(effects
				(font
					(size 1.27 1.27)
					(thickness 0.15)
				)
				(justify left)
			)
		)
		(property "Value" "Spacer_Drill3.7mm_H2.5mm_9774025151R"
			(at 87.63 215.9 0)
			(effects
				(font
					(size 1.27 1.27)
					(thickness 0.15)
				)
				(justify left)
			)
		)
		(property "Footprint" "antmicro-footprints:Spacer_Drill3.7mm_H2.5mm_9774025151R"
			(at 73.66 222.25 0)
			(effects
				(font
					(size 1.27 1.27)
					(thickness 0.15)
				)
				(justify left bottom)
				(hide yes)
			)
		)
		(property "Datasheet" "https://www.we-online.com/components/products/datasheet/9774025151R.pdf"
			(at 73.66 224.79 0)
			(effects
				(font
					(size 1.27 1.27)
					(thickness 0.15)
				)
				(justify left bottom)
				(hide yes)
			)
		)
		(property "Description" "Spacer, SMT, Non Stop, Steel, Swage Round, 5.1 mm x 2.5 mm, M2.5 Thread, WA-SMSI Series"
			(at 96.52 214.63 0)
			(effects
				(font
					(size 1.27 1.27)
				)
				(hide yes)
			)
		)
		(property "Manufacturer" "Würth Elektronik"
			(at 73.66 227.33 0)
			(effects
				(font
					(size 1.27 1.27)
					(thickness 0.15)
				)
				(justify left bottom)
				(hide yes)
			)
		)
		(property "MPN" "9774025151R"
			(at 73.66 229.87 0)
			(effects
				(font
					(size 1.27 1.27)
					(thickness 0.15)
				)
				(justify left bottom)
				(hide yes)
			)
		)
		(property "Author" "Antmicro"
			(at 73.66 232.41 0)
			(effects
				(font
					(size 1.27 1.27)
					(thickness 0.15)
				)
				(justify left bottom)
				(hide yes)
			)
		)
		(property "License" "Apache-2.0"
			(at 73.66 234.95 0)
			(effects
				(font
					(size 1.27 1.27)
					(thickness 0.15)
				)
				(justify left bottom)
				(hide yes)
			)
		)
		(pin "1"
		)
		(instances
			(project "jetson-agx-thor-baseboard"
				(path ""
					(reference "H9")
					(unit 1)
				)
			)
		)
	)
	(symbol
		(lib_id "antmicroTestPoints:TP_0.75mm_SMD")
		(at 147.32 129.54 0)
		(unit 1)
		(exclude_from_sim no)
		(in_bom no)
		(on_board yes)
		(dnp no)
		(property "Reference" "TP36"
			(at 151.13 129.54 0)
			(effects
				(font
					(size 1.27 1.27)
				)
				(justify left)
			)
		)
		(property "Value" "TP_0.75mm_SMD"
			(at 157.48 133.35 0)
			(effects
				(font
					(size 1.27 1.27)
					(thickness 0.15)
				)
				(justify left bottom)
				(hide yes)
			)
		)
		(property "Footprint" "antmicro-footprints:TP_SMD_0.75mm"
			(at 157.48 135.89 0)
			(effects
				(font
					(size 1.27 1.27)
					(thickness 0.15)
				)
				(justify left bottom)
				(hide yes)
			)
		)
		(property "Datasheet" ""
			(at 165.1 142.24 0)
			(effects
				(font
					(size 1.27 1.27)
					(thickness 0.15)
				)
				(justify left bottom)
				(hide yes)
			)
		)
		(property "Description" "SMT test point"
			(at 147.32 129.54 0)
			(effects
				(font
					(size 1.27 1.27)
				)
				(hide yes)
			)
		)
		(property "MPN" ""
			(at 158.115 140.97 0)
			(effects
				(font
					(size 1.27 1.27)
					(thickness 0.15)
				)
				(justify left bottom)
				(hide yes)
			)
		)
		(property "Manufacturer" ""
			(at 158.115 135.89 0)
			(effects
				(font
					(size 1.27 1.27)
					(thickness 0.15)
				)
				(justify left bottom)
				(hide yes)
			)
		)
		(property "Author" "Antmicro"
			(at 157.48 138.43 0)
			(effects
				(font
					(size 1.27 1.27)
					(thickness 0.15)
				)
				(justify left bottom)
				(hide yes)
			)
		)
		(property "License" "Apache-2.0"
			(at 157.48 140.97 0)
			(effects
				(font
					(size 1.27 1.27)
					(thickness 0.15)
				)
				(justify left bottom)
				(hide yes)
			)
		)
		(pin "1"
		)
		(instances
			(project "jetson-agx-thor-baseboard"
				(path ""
					(reference "TP36")
					(unit 1)
				)
			)
		)
	)
	(symbol
		(lib_id "antmicroCapacitors0402:C_220n_0402")
		(at 58.42 170.18 0)
		(unit 1)
		(exclude_from_sim no)
		(in_bom yes)
		(on_board yes)
		(dnp no)
		(property "Reference" "C184"
			(at 57.658 168.91 0)
			(effects
				(font
					(size 1.27 1.27)
					(thickness 0.15)
				)
			)
		)
		(property "Value" "C_220n_0402"
			(at 73.66 193.04 0)
			(effects
				(font
					(size 1.27 1.27)
					(thickness 0.15)
				)
				(justify left bottom)
				(hide yes)
			)
		)
		(property "Footprint" "antmicro-footprints:C_0402_1005Metric"
			(at 73.66 195.58 0)
			(effects
				(font
					(size 1.27 1.27)
					(thickness 0.15)
				)
				(justify left bottom)
				(hide yes)
			)
		)
		(property "Datasheet" "https://www.yageo.com/en/Chart/Download/pdf/CC0402KRX5R6BB224"
			(at 73.66 198.12 0)
			(effects
				(font
					(size 1.27 1.27)
					(thickness 0.15)
				)
				(justify left bottom)
				(hide yes)
			)
		)
		(property "Description" "SMD Multilayer Ceramic Capacitor, 0.22 µF, 10 V, 0402 [1005 Metric], ± 10%, X5R, CC Series"
			(at 58.42 170.18 0)
			(effects
				(font
					(size 1.27 1.27)
				)
				(hide yes)
			)
		)
		(property "MPN" "CC0402KRX5R6BB224"
			(at 73.66 200.66 0)
			(effects
				(font
					(size 1.27 1.27)
					(thickness 0.15)
				)
				(justify left bottom)
				(hide yes)
			)
		)
		(property "Val" "220n"
			(at 64.77 168.91 0)
			(effects
				(font
					(size 1.27 1.27)
					(thickness 0.15)
				)
			)
		)
		(property "Voltage" "25V"
			(at 73.66 180.34 0)
			(effects
				(font
					(size 1.27 1.27)
					(thickness 0.15)
				)
				(justify left bottom)
				(hide yes)
			)
		)
		(property "Dielectric" "X7R"
			(at 73.66 182.88 0)
			(effects
				(font
					(size 1.27 1.27)
					(thickness 0.15)
				)
				(justify left bottom)
				(hide yes)
			)
		)
		(property "Manufacturer" "YAGEO"
			(at 73.66 185.42 0)
			(effects
				(font
					(size 1.27 1.27)
					(thickness 0.15)
				)
				(justify left bottom)
				(hide yes)
			)
		)
		(property "License" "Apache-2.0"
			(at 73.66 187.96 0)
			(effects
				(font
					(size 1.27 1.27)
					(thickness 0.15)
				)
				(justify left bottom)
				(hide yes)
			)
		)
		(property "Author" "Antmicro"
			(at 73.66 190.5 0)
			(effects
				(font
					(size 1.27 1.27)
					(thickness 0.15)
				)
				(justify left bottom)
				(hide yes)
			)
		)
		(property "Public" "False"
			(at 78.74 203.2 0)
			(effects
				(font
					(size 1.27 1.27)
				)
				(justify left bottom)
				(hide yes)
			)
		)
		(pin "2"
		)
		(pin "1"
		)
		(instances
			(project "jetson-agx-thor-baseboard"
				(path ""
					(reference "C184")
					(unit 1)
				)
			)
		)
	)
	(symbol
		(lib_id "antmicroResistors0402:R_0R_0402")
		(at 229.87 172.72 0)
		(unit 1)
		(exclude_from_sim no)
		(in_bom yes)
		(on_board yes)
		(dnp no)
		(property "Reference" "R218"
			(at 227.33 171.45 0)
			(effects
				(font
					(size 1.27 1.27)
					(thickness 0.15)
				)
			)
		)
		(property "Value" "R_0R_0402"
			(at 250.19 185.42 0)
			(effects
				(font
					(size 1.27 1.27)
					(thickness 0.15)
				)
				(justify left bottom)
				(hide yes)
			)
		)
		(property "Footprint" "antmicro-footprints:R_0402_1005Metric"
			(at 250.19 187.96 0)
			(effects
				(font
					(size 1.27 1.27)
					(thickness 0.15)
				)
				(justify left bottom)
				(hide yes)
			)
		)
		(property "Datasheet" "https://industrial.panasonic.com/cdbs/www-data/pdf/RDA0000/AOA0000C301.pdf"
			(at 250.19 190.5 0)
			(effects
				(font
					(size 1.27 1.27)
					(thickness 0.15)
				)
				(justify left bottom)
				(hide yes)
			)
		)
		(property "Description" "SMD Chip Resistor, Jumper, 0 ohm, 100 mW, 0402 [1005 Metric], Thick Film, General Purpose"
			(at 229.87 172.72 0)
			(effects
				(font
					(size 1.27 1.27)
				)
				(hide yes)
			)
		)
		(property "MPN" "ERJ2GE0R00X"
			(at 250.19 193.04 0)
			(effects
				(font
					(size 1.27 1.27)
					(thickness 0.15)
				)
				(justify left bottom)
				(hide yes)
			)
		)
		(property "Manufacturer" "Panasonic"
			(at 250.19 195.58 0)
			(effects
				(font
					(size 1.27 1.27)
					(thickness 0.15)
				)
				(justify left bottom)
				(hide yes)
			)
		)
		(property "License" "Apache-2.0"
			(at 250.19 198.12 0)
			(effects
				(font
					(size 1.27 1.27)
					(thickness 0.15)
				)
				(justify left bottom)
				(hide yes)
			)
		)
		(property "Val" "0R"
			(at 236.22 171.45 0)
			(effects
				(font
					(size 1.27 1.27)
					(thickness 0.15)
				)
			)
		)
		(property "Tolerance" "~"
			(at 250.19 182.88 0)
			(effects
				(font
					(size 1.27 1.27)
				)
				(justify left bottom)
				(hide yes)
			)
		)
		(property "Current" "1A"
			(at 232.41 169.545 0)
			(effects
				(font
					(size 1.27 1.27)
					(thickness 0.15)
				)
				(hide yes)
			)
		)
		(property "Author" "Antmicro"
			(at 250.19 200.66 0)
			(effects
				(font
					(size 1.27 1.27)
					(thickness 0.15)
				)
				(justify left bottom)
				(hide yes)
			)
		)
		(property "Public" "False"
			(at 250.19 203.2 0)
			(effects
				(font
					(size 1.27 1.27)
				)
				(justify left bottom)
				(hide yes)
			)
		)
		(pin "1"
		)
		(pin "2"
		)
		(instances
			(project "jetson-agx-thor-baseboard"
				(path ""
					(reference "R218")
					(unit 1)
				)
			)
		)
	)
	(symbol
		(lib_id "antmicropower:+3V3")
		(at 363.22 165.1 0)
		(unit 1)
		(exclude_from_sim no)
		(in_bom yes)
		(on_board yes)
		(dnp no)
		(property "Reference" "#PWR0378"
			(at 363.22 168.91 0)
			(effects
				(font
					(size 1.27 1.27)
				)
				(hide yes)
			)
		)
		(property "Value" "+3V3"
			(at 363.22 161.29 0)
			(effects
				(font
					(size 1.27 1.27)
				)
			)
		)
		(property "Footprint" ""
			(at 363.22 165.1 0)
			(effects
				(font
					(size 1.27 1.27)
				)
				(hide yes)
			)
		)
		(property "Datasheet" ""
			(at 363.22 165.1 0)
			(effects
				(font
					(size 1.27 1.27)
				)
				(hide yes)
			)
		)
		(property "Description" ""
			(at 363.22 165.1 0)
			(effects
				(font
					(size 1.27 1.27)
				)
				(hide yes)
			)
		)
		(property "Author" "Antmicro"
			(at 378.46 167.64 0)
			(effects
				(font
					(size 1.27 1.27)
					(thickness 0.15)
				)
				(justify left bottom)
				(hide yes)
			)
		)
		(property "License" "Apache-2.0"
			(at 378.46 170.18 0)
			(effects
				(font
					(size 1.27 1.27)
					(thickness 0.15)
				)
				(justify left bottom)
				(hide yes)
			)
		)
		(pin "1"
		)
		(instances
			(project "jetson-agx-thor-baseboard"
				(path ""
					(reference "#PWR0378")
					(unit 1)
				)
			)
		)
	)
	(symbol
		(lib_id "antmicropower:GND")
		(at 298.45 199.39 0)
		(unit 1)
		(exclude_from_sim no)
		(in_bom yes)
		(on_board yes)
		(dnp no)
		(fields_autoplaced yes)
		(property "Reference" "#PWR0375"
			(at 298.45 205.74 0)
			(effects
				(font
					(size 1.27 1.27)
				)
				(hide yes)
			)
		)
		(property "Value" "GND"
			(at 298.45 204.47 0)
			(effects
				(font
					(size 1.27 1.27)
				)
			)
		)
		(property "Footprint" ""
			(at 298.45 199.39 0)
			(effects
				(font
					(size 1.27 1.27)
				)
				(hide yes)
			)
		)
		(property "Datasheet" ""
			(at 298.45 199.39 0)
			(effects
				(font
					(size 1.27 1.27)
				)
				(hide yes)
			)
		)
		(property "Description" ""
			(at 298.45 199.39 0)
			(effects
				(font
					(size 1.27 1.27)
				)
				(hide yes)
			)
		)
		(property "Author" "Antmicro"
			(at 307.34 207.01 0)
			(effects
				(font
					(size 1.27 1.27)
					(thickness 0.15)
				)
				(justify left bottom)
				(hide yes)
			)
		)
		(property "License" "Apache-2.0"
			(at 307.34 209.55 0)
			(effects
				(font
					(size 1.27 1.27)
					(thickness 0.15)
				)
				(justify left bottom)
				(hide yes)
			)
		)
		(pin "1"
		)
		(instances
			(project "jetson-agx-thor-baseboard"
				(path ""
					(reference "#PWR0375")
					(unit 1)
				)
			)
		)
	)
	(symbol
		(lib_id "antmicroResistors0402:R_200R_0402")
		(at 363.22 170.18 90)
		(unit 1)
		(exclude_from_sim no)
		(in_bom yes)
		(on_board yes)
		(dnp no)
		(fields_autoplaced yes)
		(property "Reference" "R221"
			(at 365.76 166.37 90)
			(effects
				(font
					(size 1.27 1.27)
				)
				(justify right)
			)
		)
		(property "Value" "R_200R_0402"
			(at 375.92 149.86 0)
			(effects
				(font
					(size 1.27 1.27)
					(thickness 0.15)
				)
				(justify left bottom)
				(hide yes)
			)
		)
		(property "Footprint" "antmicro-footprints:R_0402_1005Metric"
			(at 378.46 149.86 0)
			(effects
				(font
					(size 1.27 1.27)
					(thickness 0.15)
				)
				(justify left bottom)
				(hide yes)
			)
		)
		(property "Datasheet" "https://www.bourns.com/docs/product-datasheets/cr.pdf"
			(at 381 149.86 0)
			(effects
				(font
					(size 1.27 1.27)
					(thickness 0.15)
				)
				(justify left bottom)
				(hide yes)
			)
		)
		(property "Description" "SMD Chip Resistor, 200 ohm, ± 1%, 62.5 mW, 0402 [1005 Metric], Thick Film, General Purpose"
			(at 363.22 170.18 0)
			(effects
				(font
					(size 1.27 1.27)
				)
				(hide yes)
			)
		)
		(property "Manufacturer" "Bourns"
			(at 386.08 149.86 0)
			(effects
				(font
					(size 1.27 1.27)
					(thickness 0.15)
				)
				(justify left bottom)
				(hide yes)
			)
		)
		(property "MPN" "CR0402-FX-2000GLF"
			(at 383.54 149.86 0)
			(effects
				(font
					(size 1.27 1.27)
					(thickness 0.15)
				)
				(justify left bottom)
				(hide yes)
			)
		)
		(property "Val" "200R"
			(at 365.76 168.91 90)
			(effects
				(font
					(size 1.27 1.27)
					(thickness 0.15)
				)
				(justify right)
			)
		)
		(property "License" "Apache-2.0"
			(at 388.62 149.86 0)
			(effects
				(font
					(size 1.27 1.27)
					(thickness 0.15)
				)
				(justify left bottom)
				(hide yes)
			)
		)
		(property "Author" "Antmicro"
			(at 391.16 149.86 0)
			(effects
				(font
					(size 1.27 1.27)
					(thickness 0.15)
				)
				(justify left bottom)
				(hide yes)
			)
		)
		(property "Tolerance" "1%"
			(at 373.38 149.86 0)
			(effects
				(font
					(size 1.27 1.27)
				)
				(justify left bottom)
				(hide yes)
			)
		)
		(pin "1"
		)
		(pin "2"
		)
		(instances
			(project "jetson-agx-thor-baseboard"
				(path ""
					(reference "R221")
					(unit 1)
				)
			)
		)
	)
	(symbol
		(lib_id "antmicroLEDIndicationDiscrete:LED_G_0603_LTST-C190GKT")
		(at 375.92 176.53 90)
		(unit 1)
		(exclude_from_sim no)
		(in_bom yes)
		(on_board yes)
		(dnp no)
		(property "Reference" "D34"
			(at 372.11 172.72 90)
			(effects
				(font
					(size 1.27 1.27)
				)
				(justify left)
			)
		)
		(property "Value" "LED_G_0603_LTST-C190GKT"
			(at 383.54 153.67 0)
			(effects
				(font
					(size 1.27 1.27)
					(thickness 0.15)
				)
				(justify left bottom)
				(hide yes)
			)
		)
		(property "Footprint" "antmicro-footprints:LED_0603_1608Metric_G"
			(at 386.08 153.67 0)
			(effects
				(font
					(size 1.27 1.27)
					(thickness 0.15)
				)
				(justify left bottom)
				(hide yes)
			)
		)
		(property "Datasheet" "https://media.digikey.com/pdf/Data%20Sheets/Lite-On%20PDFs/LTST-C190GKT.pdf"
			(at 388.62 153.67 0)
			(effects
				(font
					(size 1.27 1.27)
					(thickness 0.15)
				)
				(justify left bottom)
				(hide yes)
			)
		)
		(property "Description" "LED, Green, SMD, 0603, 20 mA, 2.1 V, 569 nm"
			(at 375.92 176.53 0)
			(effects
				(font
					(size 1.27 1.27)
				)
				(hide yes)
			)
		)
		(property "MPN" "LTST-C190GKT"
			(at 379.095 182.88 0)
			(effects
				(font
					(size 1.27 1.27)
					(thickness 0.15)
				)
				(justify left)
				(hide yes)
			)
		)
		(property "Manufacturer" "Lite-On"
			(at 393.7 153.67 0)
			(effects
				(font
					(size 1.27 1.27)
					(thickness 0.15)
				)
				(justify left bottom)
				(hide yes)
			)
		)
		(property "Author" "Antmicro"
			(at 396.24 153.67 0)
			(effects
				(font
					(size 1.27 1.27)
					(thickness 0.15)
				)
				(justify left bottom)
				(hide yes)
			)
		)
		(property "License" "Apache-2.0"
			(at 398.78 153.67 0)
			(effects
				(font
					(size 1.27 1.27)
					(thickness 0.15)
				)
				(justify left bottom)
				(hide yes)
			)
		)
		(property "Public" "False"
			(at 393.7 156.21 0)
			(effects
				(font
					(size 1.27 1.27)
				)
				(justify left bottom)
				(hide yes)
			)
		)
		(property "Color" "Green"
			(at 372.11 175.26 90)
			(effects
				(font
					(size 1.27 1.27)
				)
				(justify left)
			)
		)
		(pin "1"
		)
		(pin "2"
		)
		(instances
			(project "jetson-agx-thor-baseboard"
				(path ""
					(reference "D34")
					(unit 1)
				)
			)
		)
	)
	(symbol
		(lib_id "antmicroResistors0402:R_0R_0402")
		(at 224.79 93.98 0)
		(unit 1)
		(exclude_from_sim no)
		(in_bom yes)
		(on_board yes)
		(dnp no)
		(property "Reference" "R214"
			(at 222.504 92.71 0)
			(effects
				(font
					(size 1.27 1.27)
					(thickness 0.15)
				)
			)
		)
		(property "Value" "R_0R_0402"
			(at 245.11 106.68 0)
			(effects
				(font
					(size 1.27 1.27)
					(thickness 0.15)
				)
				(justify left bottom)
				(hide yes)
			)
		)
		(property "Footprint" "antmicro-footprints:R_0402_1005Metric"
			(at 245.11 109.22 0)
			(effects
				(font
					(size 1.27 1.27)
					(thickness 0.15)
				)
				(justify left bottom)
				(hide yes)
			)
		)
		(property "Datasheet" "https://industrial.panasonic.com/cdbs/www-data/pdf/RDA0000/AOA0000C301.pdf"
			(at 245.11 111.76 0)
			(effects
				(font
					(size 1.27 1.27)
					(thickness 0.15)
				)
				(justify left bottom)
				(hide yes)
			)
		)
		(property "Description" "SMD Chip Resistor, Jumper, 0 ohm, 100 mW, 0402 [1005 Metric], Thick Film, General Purpose"
			(at 224.79 93.98 0)
			(effects
				(font
					(size 1.27 1.27)
				)
				(hide yes)
			)
		)
		(property "MPN" "ERJ2GE0R00X"
			(at 245.11 114.3 0)
			(effects
				(font
					(size 1.27 1.27)
					(thickness 0.15)
				)
				(justify left bottom)
				(hide yes)
			)
		)
		(property "Manufacturer" "Panasonic"
			(at 245.11 116.84 0)
			(effects
				(font
					(size 1.27 1.27)
					(thickness 0.15)
				)
				(justify left bottom)
				(hide yes)
			)
		)
		(property "License" "Apache-2.0"
			(at 245.11 119.38 0)
			(effects
				(font
					(size 1.27 1.27)
					(thickness 0.15)
				)
				(justify left bottom)
				(hide yes)
			)
		)
		(property "Author" "Antmicro"
			(at 245.11 121.92 0)
			(effects
				(font
					(size 1.27 1.27)
					(thickness 0.15)
				)
				(justify left bottom)
				(hide yes)
			)
		)
		(property "Val" "0R"
			(at 231.14 92.71 0)
			(effects
				(font
					(size 1.27 1.27)
					(thickness 0.15)
				)
			)
		)
		(property "Tolerance" "~"
			(at 245.11 104.14 0)
			(effects
				(font
					(size 1.27 1.27)
				)
				(justify left bottom)
				(hide yes)
			)
		)
		(property "Current" "1A"
			(at 245.11 124.46 0)
			(effects
				(font
					(size 1.27 1.27)
					(thickness 0.15)
				)
				(justify left bottom)
				(hide yes)
			)
		)
		(pin "2"
		)
		(pin "1"
		)
		(instances
			(project "jetson-agx-thor-baseboard"
				(path ""
					(reference "R214")
					(unit 1)
				)
			)
		)
	)
	(symbol
		(lib_id "antmicroCapacitors0603:C_22u_16V_0603")
		(at 300.99 93.98 90)
		(unit 1)
		(exclude_from_sim no)
		(in_bom yes)
		(on_board yes)
		(dnp no)
		(fields_autoplaced yes)
		(property "Reference" "C71"
			(at 303.53 90.1636 90)
			(effects
				(font
					(size 1.27 1.27)
					(thickness 0.15)
				)
				(justify right)
			)
		)
		(property "Value" "C_22u_16V_0603"
			(at 311.15 73.66 0)
			(effects
				(font
					(size 1.27 1.27)
					(thickness 0.15)
				)
				(justify left bottom)
				(hide yes)
			)
		)
		(property "Footprint" "antmicro-footprints:C_0603_1608Metric_EIA"
			(at 313.69 73.66 0)
			(effects
				(font
					(size 1.27 1.27)
					(thickness 0.15)
				)
				(justify left bottom)
				(hide yes)
			)
		)
		(property "Datasheet" "https://product.samsungsem.com/mlcc/CL10A226MO7JZN.do"
			(at 316.23 73.66 0)
			(effects
				(font
					(size 1.27 1.27)
					(thickness 0.15)
				)
				(justify left bottom)
				(hide yes)
			)
		)
		(property "Description" "SMD Multilayer Ceramic Capacitor"
			(at 300.99 93.98 0)
			(effects
				(font
					(size 1.27 1.27)
				)
				(hide yes)
			)
		)
		(property "MPN" "CL10A226MO7JZNC"
			(at 318.77 73.66 0)
			(effects
				(font
					(size 1.27 1.27)
					(thickness 0.15)
				)
				(justify left bottom)
				(hide yes)
			)
		)
		(property "Manufacturer" "Samsung Electro-Mechanics"
			(at 321.31 73.66 0)
			(effects
				(font
					(size 1.27 1.27)
					(thickness 0.15)
				)
				(justify left bottom)
				(hide yes)
			)
		)
		(property "License" "Apache-2.0"
			(at 323.85 73.66 0)
			(effects
				(font
					(size 1.27 1.27)
					(thickness 0.15)
				)
				(justify left bottom)
				(hide yes)
			)
		)
		(property "Author" "Antmicro"
			(at 326.39 73.66 0)
			(effects
				(font
					(size 1.27 1.27)
					(thickness 0.15)
				)
				(justify left bottom)
				(hide yes)
			)
		)
		(property "Val" "22u"
			(at 303.53 92.7036 90)
			(effects
				(font
					(size 1.27 1.27)
					(thickness 0.15)
				)
				(justify right)
			)
		)
		(property "Voltage" "16V"
			(at 328.93 73.66 0)
			(effects
				(font
					(size 1.27 1.27)
				)
				(justify left bottom)
				(hide yes)
			)
		)
		(property "Dielectric" ""
			(at 331.47 73.66 0)
			(effects
				(font
					(size 1.27 1.27)
				)
				(justify left bottom)
				(hide yes)
			)
		)
		(pin "2"
		)
		(pin "1"
		)
		(instances
			(project ""
				(path ""
					(reference "C71")
					(unit 1)
				)
			)
		)
	)
	(symbol
		(lib_id "antmicroCapacitors0402:C_220n_0402")
		(at 58.42 139.7 0)
		(unit 1)
		(exclude_from_sim no)
		(in_bom yes)
		(on_board yes)
		(dnp no)
		(property "Reference" "C182"
			(at 57.658 138.43 0)
			(effects
				(font
					(size 1.27 1.27)
					(thickness 0.15)
				)
			)
		)
		(property "Value" "C_220n_0402"
			(at 73.66 162.56 0)
			(effects
				(font
					(size 1.27 1.27)
					(thickness 0.15)
				)
				(justify left bottom)
				(hide yes)
			)
		)
		(property "Footprint" "antmicro-footprints:C_0402_1005Metric"
			(at 73.66 165.1 0)
			(effects
				(font
					(size 1.27 1.27)
					(thickness 0.15)
				)
				(justify left bottom)
				(hide yes)
			)
		)
		(property "Datasheet" "https://www.yageo.com/en/Chart/Download/pdf/CC0402KRX5R6BB224"
			(at 73.66 167.64 0)
			(effects
				(font
					(size 1.27 1.27)
					(thickness 0.15)
				)
				(justify left bottom)
				(hide yes)
			)
		)
		(property "Description" "SMD Multilayer Ceramic Capacitor, 0.22 µF, 10 V, 0402 [1005 Metric], ± 10%, X5R, CC Series"
			(at 58.42 139.7 0)
			(effects
				(font
					(size 1.27 1.27)
				)
				(hide yes)
			)
		)
		(property "MPN" "CC0402KRX5R6BB224"
			(at 73.66 170.18 0)
			(effects
				(font
					(size 1.27 1.27)
					(thickness 0.15)
				)
				(justify left bottom)
				(hide yes)
			)
		)
		(property "Val" "220n"
			(at 64.77 138.43 0)
			(effects
				(font
					(size 1.27 1.27)
					(thickness 0.15)
				)
			)
		)
		(property "Voltage" "25V"
			(at 73.66 149.86 0)
			(effects
				(font
					(size 1.27 1.27)
					(thickness 0.15)
				)
				(justify left bottom)
				(hide yes)
			)
		)
		(property "Dielectric" "X7R"
			(at 73.66 152.4 0)
			(effects
				(font
					(size 1.27 1.27)
					(thickness 0.15)
				)
				(justify left bottom)
				(hide yes)
			)
		)
		(property "Manufacturer" "YAGEO"
			(at 73.66 154.94 0)
			(effects
				(font
					(size 1.27 1.27)
					(thickness 0.15)
				)
				(justify left bottom)
				(hide yes)
			)
		)
		(property "License" "Apache-2.0"
			(at 73.66 157.48 0)
			(effects
				(font
					(size 1.27 1.27)
					(thickness 0.15)
				)
				(justify left bottom)
				(hide yes)
			)
		)
		(property "Author" "Antmicro"
			(at 73.66 160.02 0)
			(effects
				(font
					(size 1.27 1.27)
					(thickness 0.15)
				)
				(justify left bottom)
				(hide yes)
			)
		)
		(property "Public" "False"
			(at 78.74 172.72 0)
			(effects
				(font
					(size 1.27 1.27)
				)
				(justify left bottom)
				(hide yes)
			)
		)
		(pin "2"
		)
		(pin "1"
		)
		(instances
			(project "jetson-agx-thor-baseboard"
				(path ""
					(reference "C182")
					(unit 1)
				)
			)
		)
	)
	(symbol
		(lib_id "antmicroResistors0402:R_0R_0402")
		(at 224.79 96.52 0)
		(unit 1)
		(exclude_from_sim no)
		(in_bom yes)
		(on_board yes)
		(dnp no)
		(property "Reference" "R215"
			(at 222.504 95.25 0)
			(effects
				(font
					(size 1.27 1.27)
					(thickness 0.15)
				)
			)
		)
		(property "Value" "R_0R_0402"
			(at 245.11 109.22 0)
			(effects
				(font
					(size 1.27 1.27)
					(thickness 0.15)
				)
				(justify left bottom)
				(hide yes)
			)
		)
		(property "Footprint" "antmicro-footprints:R_0402_1005Metric"
			(at 245.11 111.76 0)
			(effects
				(font
					(size 1.27 1.27)
					(thickness 0.15)
				)
				(justify left bottom)
				(hide yes)
			)
		)
		(property "Datasheet" "https://industrial.panasonic.com/cdbs/www-data/pdf/RDA0000/AOA0000C301.pdf"
			(at 245.11 114.3 0)
			(effects
				(font
					(size 1.27 1.27)
					(thickness 0.15)
				)
				(justify left bottom)
				(hide yes)
			)
		)
		(property "Description" "SMD Chip Resistor, Jumper, 0 ohm, 100 mW, 0402 [1005 Metric], Thick Film, General Purpose"
			(at 224.79 96.52 0)
			(effects
				(font
					(size 1.27 1.27)
				)
				(hide yes)
			)
		)
		(property "MPN" "ERJ2GE0R00X"
			(at 245.11 116.84 0)
			(effects
				(font
					(size 1.27 1.27)
					(thickness 0.15)
				)
				(justify left bottom)
				(hide yes)
			)
		)
		(property "Manufacturer" "Panasonic"
			(at 245.11 119.38 0)
			(effects
				(font
					(size 1.27 1.27)
					(thickness 0.15)
				)
				(justify left bottom)
				(hide yes)
			)
		)
		(property "License" "Apache-2.0"
			(at 245.11 121.92 0)
			(effects
				(font
					(size 1.27 1.27)
					(thickness 0.15)
				)
				(justify left bottom)
				(hide yes)
			)
		)
		(property "Author" "Antmicro"
			(at 245.11 124.46 0)
			(effects
				(font
					(size 1.27 1.27)
					(thickness 0.15)
				)
				(justify left bottom)
				(hide yes)
			)
		)
		(property "Val" "0R"
			(at 231.14 95.25 0)
			(effects
				(font
					(size 1.27 1.27)
					(thickness 0.15)
				)
			)
		)
		(property "Tolerance" "~"
			(at 245.11 106.68 0)
			(effects
				(font
					(size 1.27 1.27)
				)
				(justify left bottom)
				(hide yes)
			)
		)
		(property "Current" "1A"
			(at 245.11 127 0)
			(effects
				(font
					(size 1.27 1.27)
					(thickness 0.15)
				)
				(justify left bottom)
				(hide yes)
			)
		)
		(pin "2"
		)
		(pin "1"
		)
		(instances
			(project "jetson-agx-thor-baseboard"
				(path ""
					(reference "R215")
					(unit 1)
				)
			)
		)
	)
	(symbol
		(lib_id "antmicropower:GND")
		(at 300.99 95.25 0)
		(unit 1)
		(exclude_from_sim no)
		(in_bom yes)
		(on_board yes)
		(dnp no)
		(property "Reference" "#PWR0376"
			(at 300.99 101.6 0)
			(effects
				(font
					(size 1.27 1.27)
				)
				(hide yes)
			)
		)
		(property "Value" "GND"
			(at 300.99 99.06 0)
			(effects
				(font
					(size 1.27 1.27)
				)
			)
		)
		(property "Footprint" ""
			(at 300.99 95.25 0)
			(effects
				(font
					(size 1.27 1.27)
				)
				(hide yes)
			)
		)
		(property "Datasheet" ""
			(at 300.99 95.25 0)
			(effects
				(font
					(size 1.27 1.27)
				)
				(hide yes)
			)
		)
		(property "Description" ""
			(at 300.99 95.25 0)
			(effects
				(font
					(size 1.27 1.27)
				)
				(hide yes)
			)
		)
		(property "Author" "Antmicro"
			(at 309.88 102.87 0)
			(effects
				(font
					(size 1.27 1.27)
					(thickness 0.15)
				)
				(justify left bottom)
				(hide yes)
			)
		)
		(property "License" "Apache-2.0"
			(at 309.88 105.41 0)
			(effects
				(font
					(size 1.27 1.27)
					(thickness 0.15)
				)
				(justify left bottom)
				(hide yes)
			)
		)
		(pin "1"
		)
		(instances
			(project "jetson-agx-thor-baseboard"
				(path ""
					(reference "#PWR0376")
					(unit 1)
				)
			)
		)
	)
	(symbol
		(lib_id "antmicroCapacitors0603:C_22u_16V_0603")
		(at 167.64 100.33 90)
		(mirror x)
		(unit 1)
		(exclude_from_sim no)
		(in_bom yes)
		(on_board yes)
		(dnp no)
		(fields_autoplaced yes)
		(property "Reference" "C193"
			(at 170.18 101.6063 90)
			(effects
				(font
					(size 1.27 1.27)
				)
				(justify right)
			)
		)
		(property "Value" "C_22u_16V_0603"
			(at 177.8 120.65 0)
			(effects
				(font
					(size 1.27 1.27)
					(thickness 0.15)
				)
				(justify left bottom)
				(hide yes)
			)
		)
		(property "Footprint" "antmicro-footprints:C_0603_1608Metric_EIA"
			(at 180.34 120.65 0)
			(effects
				(font
					(size 1.27 1.27)
					(thickness 0.15)
				)
				(justify left bottom)
				(hide yes)
			)
		)
		(property "Datasheet" "https://product.samsungsem.com/mlcc/CL10A226MO7JZN.do"
			(at 182.88 120.65 0)
			(effects
				(font
					(size 1.27 1.27)
					(thickness 0.15)
				)
				(justify left bottom)
				(hide yes)
			)
		)
		(property "Description" "SMD Multilayer Ceramic Capacitor"
			(at 167.64 100.33 0)
			(effects
				(font
					(size 1.27 1.27)
				)
				(hide yes)
			)
		)
		(property "Manufacturer" "Samsung Electro-Mechanics"
			(at 187.96 120.65 0)
			(effects
				(font
					(size 1.27 1.27)
					(thickness 0.15)
				)
				(justify left bottom)
				(hide yes)
			)
		)
		(property "MPN" "CL10A226MO7JZNC"
			(at 185.42 120.65 0)
			(effects
				(font
					(size 1.27 1.27)
					(thickness 0.15)
				)
				(justify left bottom)
				(hide yes)
			)
		)
		(property "Val" "22u"
			(at 170.18 104.1463 90)
			(effects
				(font
					(size 1.27 1.27)
					(thickness 0.15)
				)
				(justify right)
			)
		)
		(property "License" "Apache-2.0"
			(at 190.5 120.65 0)
			(effects
				(font
					(size 1.27 1.27)
					(thickness 0.15)
				)
				(justify left bottom)
				(hide yes)
			)
		)
		(property "Author" "Antmicro"
			(at 193.04 120.65 0)
			(effects
				(font
					(size 1.27 1.27)
					(thickness 0.15)
				)
				(justify left bottom)
				(hide yes)
			)
		)
		(property "Voltage" "16V"
			(at 195.58 120.65 0)
			(effects
				(font
					(size 1.27 1.27)
				)
				(justify left bottom)
				(hide yes)
			)
		)
		(property "Dielectric" "template_dielectric"
			(at 198.12 120.65 0)
			(effects
				(font
					(size 1.27 1.27)
				)
				(justify left bottom)
				(hide yes)
			)
		)
		(pin "1"
		)
		(pin "2"
		)
		(instances
			(project "jetson-agx-thor-baseboard"
				(path ""
					(reference "C193")
					(unit 1)
				)
			)
		)
	)
	(symbol
		(lib_id "antmicropower:GND")
		(at 93.98 270.51 0)
		(unit 1)
		(exclude_from_sim no)
		(in_bom yes)
		(on_board yes)
		(dnp no)
		(property "Reference" "#PWR0362"
			(at 93.98 276.86 0)
			(effects
				(font
					(size 1.27 1.27)
				)
				(justify left bottom)
				(hide yes)
			)
		)
		(property "Value" "GND"
			(at 93.98 274.32 0)
			(effects
				(font
					(size 1.27 1.27)
					(thickness 0.15)
				)
			)
		)
		(property "Footprint" ""
			(at 102.87 278.13 0)
			(effects
				(font
					(size 1.27 1.27)
					(thickness 0.15)
				)
				(justify left bottom)
				(hide yes)
			)
		)
		(property "Datasheet" ""
			(at 102.87 283.21 0)
			(effects
				(font
					(size 1.27 1.27)
					(thickness 0.15)
				)
				(justify left bottom)
				(hide yes)
			)
		)
		(property "Description" ""
			(at 93.98 270.51 0)
			(effects
				(font
					(size 1.27 1.27)
				)
				(hide yes)
			)
		)
		(property "Author" "Antmicro"
			(at 102.87 278.13 0)
			(effects
				(font
					(size 1.27 1.27)
					(thickness 0.15)
				)
				(justify left bottom)
				(hide yes)
			)
		)
		(property "License" "Apache-2.0"
			(at 102.87 280.67 0)
			(effects
				(font
					(size 1.27 1.27)
					(thickness 0.15)
				)
				(justify left bottom)
				(hide yes)
			)
		)
		(pin "1"
		)
		(instances
			(project "jetson-agx-thor-baseboard"
				(path ""
					(reference "#PWR0362")
					(unit 1)
				)
			)
		)
	)
	(symbol
		(lib_id "antmicropower:+3V3")
		(at 246.38 85.09 0)
		(unit 1)
		(exclude_from_sim no)
		(in_bom yes)
		(on_board yes)
		(dnp no)
		(property "Reference" "#PWR0373"
			(at 246.38 88.9 0)
			(effects
				(font
					(size 1.27 1.27)
				)
				(justify left bottom)
				(hide yes)
			)
		)
		(property "Value" "+3V3"
			(at 243.078 81.788 0)
			(effects
				(font
					(size 1.27 1.27)
				)
				(justify left bottom)
			)
		)
		(property "Footprint" ""
			(at 246.38 85.09 0)
			(effects
				(font
					(size 1.27 1.27)
				)
				(justify left bottom)
				(hide yes)
			)
		)
		(property "Datasheet" ""
			(at 246.38 85.09 0)
			(effects
				(font
					(size 1.27 1.27)
				)
				(justify left bottom)
				(hide yes)
			)
		)
		(property "Description" ""
			(at 246.38 85.09 0)
			(effects
				(font
					(size 1.27 1.27)
				)
				(hide yes)
			)
		)
		(property "Author" "Antmicro"
			(at 261.62 87.63 0)
			(effects
				(font
					(size 1.27 1.27)
					(thickness 0.15)
				)
				(justify left bottom)
				(hide yes)
			)
		)
		(property "License" "Apache-2.0"
			(at 261.62 90.17 0)
			(effects
				(font
					(size 1.27 1.27)
					(thickness 0.15)
				)
				(justify left bottom)
				(hide yes)
			)
		)
		(pin "1"
		)
		(instances
			(project "jetson-agx-thor-baseboard"
				(path ""
					(reference "#PWR0373")
					(unit 1)
				)
			)
		)
	)
	(symbol
		(lib_id "antmicropower:GND")
		(at 100.33 270.51 0)
		(unit 1)
		(exclude_from_sim no)
		(in_bom yes)
		(on_board yes)
		(dnp no)
		(property "Reference" "#PWR0363"
			(at 100.33 276.86 0)
			(effects
				(font
					(size 1.27 1.27)
				)
				(justify left bottom)
				(hide yes)
			)
		)
		(property "Value" "GND"
			(at 100.33 274.32 0)
			(effects
				(font
					(size 1.27 1.27)
					(thickness 0.15)
				)
			)
		)
		(property "Footprint" ""
			(at 109.22 278.13 0)
			(effects
				(font
					(size 1.27 1.27)
					(thickness 0.15)
				)
				(justify left bottom)
				(hide yes)
			)
		)
		(property "Datasheet" ""
			(at 109.22 283.21 0)
			(effects
				(font
					(size 1.27 1.27)
					(thickness 0.15)
				)
				(justify left bottom)
				(hide yes)
			)
		)
		(property "Description" ""
			(at 100.33 270.51 0)
			(effects
				(font
					(size 1.27 1.27)
				)
				(hide yes)
			)
		)
		(property "Author" "Antmicro"
			(at 109.22 278.13 0)
			(effects
				(font
					(size 1.27 1.27)
					(thickness 0.15)
				)
				(justify left bottom)
				(hide yes)
			)
		)
		(property "License" "Apache-2.0"
			(at 109.22 280.67 0)
			(effects
				(font
					(size 1.27 1.27)
					(thickness 0.15)
				)
				(justify left bottom)
				(hide yes)
			)
		)
		(pin "1"
		)
		(instances
			(project "jetson-agx-thor-baseboard"
				(path ""
					(reference "#PWR0363")
					(unit 1)
				)
			)
		)
	)
	(symbol
		(lib_id "antmicropower:+3V3")
		(at 375.92 165.1 0)
		(unit 1)
		(exclude_from_sim no)
		(in_bom yes)
		(on_board yes)
		(dnp no)
		(property "Reference" "#PWR0382"
			(at 375.92 168.91 0)
			(effects
				(font
					(size 1.27 1.27)
				)
				(hide yes)
			)
		)
		(property "Value" "+3V3"
			(at 375.92 161.29 0)
			(effects
				(font
					(size 1.27 1.27)
				)
			)
		)
		(property "Footprint" ""
			(at 375.92 165.1 0)
			(effects
				(font
					(size 1.27 1.27)
				)
				(hide yes)
			)
		)
		(property "Datasheet" ""
			(at 375.92 165.1 0)
			(effects
				(font
					(size 1.27 1.27)
				)
				(hide yes)
			)
		)
		(property "Description" ""
			(at 375.92 165.1 0)
			(effects
				(font
					(size 1.27 1.27)
				)
				(hide yes)
			)
		)
		(property "Author" "Antmicro"
			(at 391.16 167.64 0)
			(effects
				(font
					(size 1.27 1.27)
					(thickness 0.15)
				)
				(justify left bottom)
				(hide yes)
			)
		)
		(property "License" "Apache-2.0"
			(at 391.16 170.18 0)
			(effects
				(font
					(size 1.27 1.27)
					(thickness 0.15)
				)
				(justify left bottom)
				(hide yes)
			)
		)
		(pin "1"
		)
		(instances
			(project "jetson-agx-thor-baseboard"
				(path ""
					(reference "#PWR0382")
					(unit 1)
				)
			)
		)
	)
	(symbol
		(lib_id "antmicropower:+3V3")
		(at 132.08 140.97 0)
		(unit 1)
		(exclude_from_sim no)
		(in_bom yes)
		(on_board yes)
		(dnp no)
		(property "Reference" "#PWR0366"
			(at 132.08 144.78 0)
			(effects
				(font
					(size 1.27 1.27)
				)
				(justify left bottom)
				(hide yes)
			)
		)
		(property "Value" "+3V3"
			(at 128.905 137.795 0)
			(effects
				(font
					(size 1.27 1.27)
					(thickness 0.15)
				)
				(justify left bottom)
			)
		)
		(property "Footprint" ""
			(at 147.32 148.59 0)
			(effects
				(font
					(size 1.27 1.27)
					(thickness 0.15)
				)
				(justify left bottom)
				(hide yes)
			)
		)
		(property "Datasheet" ""
			(at 147.32 151.13 0)
			(effects
				(font
					(size 1.27 1.27)
					(thickness 0.15)
				)
				(justify left bottom)
				(hide yes)
			)
		)
		(property "Description" ""
			(at 132.08 140.97 0)
			(effects
				(font
					(size 1.27 1.27)
				)
				(hide yes)
			)
		)
		(property "Author" "Antmicro"
			(at 147.32 143.51 0)
			(effects
				(font
					(size 1.27 1.27)
					(thickness 0.15)
				)
				(justify left bottom)
				(hide yes)
			)
		)
		(property "License" "Apache-2.0"
			(at 147.32 146.05 0)
			(effects
				(font
					(size 1.27 1.27)
					(thickness 0.15)
				)
				(justify left bottom)
				(hide yes)
			)
		)
		(pin "1"
		)
		(instances
			(project "jetson-agx-thor-baseboard"
				(path ""
					(reference "#PWR0366")
					(unit 1)
				)
			)
		)
	)
	(symbol
		(lib_id "antmicropower:GND")
		(at 137.16 105.41 0)
		(unit 1)
		(exclude_from_sim no)
		(in_bom yes)
		(on_board yes)
		(dnp no)
		(property "Reference" "#PWR0368"
			(at 137.16 111.76 0)
			(effects
				(font
					(size 1.27 1.27)
				)
				(justify left bottom)
				(hide yes)
			)
		)
		(property "Value" "GND"
			(at 135.255 109.855 0)
			(effects
				(font
					(size 1.27 1.27)
					(thickness 0.15)
				)
				(justify left bottom)
			)
		)
		(property "Footprint" ""
			(at 146.05 113.03 0)
			(effects
				(font
					(size 1.27 1.27)
					(thickness 0.15)
				)
				(justify left bottom)
				(hide yes)
			)
		)
		(property "Datasheet" ""
			(at 146.05 118.11 0)
			(effects
				(font
					(size 1.27 1.27)
					(thickness 0.15)
				)
				(justify left bottom)
				(hide yes)
			)
		)
		(property "Description" ""
			(at 137.16 105.41 0)
			(effects
				(font
					(size 1.27 1.27)
				)
				(hide yes)
			)
		)
		(property "Author" "Antmicro"
			(at 146.05 113.03 0)
			(effects
				(font
					(size 1.27 1.27)
					(thickness 0.15)
				)
				(justify left bottom)
				(hide yes)
			)
		)
		(property "License" "Apache-2.0"
			(at 146.05 115.57 0)
			(effects
				(font
					(size 1.27 1.27)
					(thickness 0.15)
				)
				(justify left bottom)
				(hide yes)
			)
		)
		(pin "1"
		)
		(instances
			(project "jetson-agx-thor-baseboard"
				(path ""
					(reference "#PWR0368")
					(unit 1)
				)
			)
		)
	)
	(symbol
		(lib_id "antmicroCapacitors0402:C_220n_0402")
		(at 227.33 114.3 0)
		(unit 1)
		(exclude_from_sim no)
		(in_bom yes)
		(on_board yes)
		(dnp no)
		(property "Reference" "C196"
			(at 226.822 113.03 0)
			(effects
				(font
					(size 1.27 1.27)
					(thickness 0.15)
				)
			)
		)
		(property "Value" "C_220n_0402"
			(at 242.57 137.16 0)
			(effects
				(font
					(size 1.27 1.27)
					(thickness 0.15)
				)
				(justify left bottom)
				(hide yes)
			)
		)
		(property "Footprint" "antmicro-footprints:C_0402_1005Metric"
			(at 242.57 139.7 0)
			(effects
				(font
					(size 1.27 1.27)
					(thickness 0.15)
				)
				(justify left bottom)
				(hide yes)
			)
		)
		(property "Datasheet" "https://www.yageo.com/en/Chart/Download/pdf/CC0402KRX5R6BB224"
			(at 242.57 142.24 0)
			(effects
				(font
					(size 1.27 1.27)
					(thickness 0.15)
				)
				(justify left bottom)
				(hide yes)
			)
		)
		(property "Description" "SMD Multilayer Ceramic Capacitor, 0.22 µF, 10 V, 0402 [1005 Metric], ± 10%, X5R, CC Series"
			(at 227.33 114.3 0)
			(effects
				(font
					(size 1.27 1.27)
				)
				(hide yes)
			)
		)
		(property "MPN" "CC0402KRX5R6BB224"
			(at 242.57 144.78 0)
			(effects
				(font
					(size 1.27 1.27)
					(thickness 0.15)
				)
				(justify left bottom)
				(hide yes)
			)
		)
		(property "Val" "220n"
			(at 233.68 113.03 0)
			(effects
				(font
					(size 1.27 1.27)
					(thickness 0.15)
				)
			)
		)
		(property "Voltage" "25V"
			(at 242.57 124.46 0)
			(effects
				(font
					(size 1.27 1.27)
					(thickness 0.15)
				)
				(justify left bottom)
				(hide yes)
			)
		)
		(property "Dielectric" "X7R"
			(at 242.57 127 0)
			(effects
				(font
					(size 1.27 1.27)
					(thickness 0.15)
				)
				(justify left bottom)
				(hide yes)
			)
		)
		(property "Manufacturer" "YAGEO"
			(at 242.57 129.54 0)
			(effects
				(font
					(size 1.27 1.27)
					(thickness 0.15)
				)
				(justify left bottom)
				(hide yes)
			)
		)
		(property "License" "Apache-2.0"
			(at 242.57 132.08 0)
			(effects
				(font
					(size 1.27 1.27)
					(thickness 0.15)
				)
				(justify left bottom)
				(hide yes)
			)
		)
		(property "Author" "Antmicro"
			(at 242.57 134.62 0)
			(effects
				(font
					(size 1.27 1.27)
					(thickness 0.15)
				)
				(justify left bottom)
				(hide yes)
			)
		)
		(property "Public" "False"
			(at 247.65 147.32 0)
			(effects
				(font
					(size 1.27 1.27)
				)
				(justify left bottom)
				(hide yes)
			)
		)
		(pin "2"
		)
		(pin "1"
		)
		(instances
			(project "jetson-agx-thor-baseboard"
				(path ""
					(reference "C196")
					(unit 1)
				)
			)
		)
	)
	(symbol
		(lib_id "antmicroResistors0402:R_0R_0402")
		(at 62.23 107.95 0)
		(unit 1)
		(exclude_from_sim no)
		(in_bom yes)
		(on_board yes)
		(dnp no)
		(property "Reference" "R208"
			(at 59.69 106.68 0)
			(effects
				(font
					(size 1.27 1.27)
					(thickness 0.15)
				)
			)
		)
		(property "Value" "R_0R_0402"
			(at 82.55 120.65 0)
			(effects
				(font
					(size 1.27 1.27)
					(thickness 0.15)
				)
				(justify left bottom)
				(hide yes)
			)
		)
		(property "Footprint" "antmicro-footprints:R_0402_1005Metric"
			(at 82.55 123.19 0)
			(effects
				(font
					(size 1.27 1.27)
					(thickness 0.15)
				)
				(justify left bottom)
				(hide yes)
			)
		)
		(property "Datasheet" "https://industrial.panasonic.com/cdbs/www-data/pdf/RDA0000/AOA0000C301.pdf"
			(at 82.55 125.73 0)
			(effects
				(font
					(size 1.27 1.27)
					(thickness 0.15)
				)
				(justify left bottom)
				(hide yes)
			)
		)
		(property "Description" "SMD Chip Resistor, Jumper, 0 ohm, 100 mW, 0402 [1005 Metric], Thick Film, General Purpose"
			(at 62.23 107.95 0)
			(effects
				(font
					(size 1.27 1.27)
				)
				(hide yes)
			)
		)
		(property "MPN" "ERJ2GE0R00X"
			(at 82.55 128.27 0)
			(effects
				(font
					(size 1.27 1.27)
					(thickness 0.15)
				)
				(justify left bottom)
				(hide yes)
			)
		)
		(property "Manufacturer" "Panasonic"
			(at 82.55 130.81 0)
			(effects
				(font
					(size 1.27 1.27)
					(thickness 0.15)
				)
				(justify left bottom)
				(hide yes)
			)
		)
		(property "License" "Apache-2.0"
			(at 82.55 133.35 0)
			(effects
				(font
					(size 1.27 1.27)
					(thickness 0.15)
				)
				(justify left bottom)
				(hide yes)
			)
		)
		(property "Author" "Antmicro"
			(at 82.55 135.89 0)
			(effects
				(font
					(size 1.27 1.27)
					(thickness 0.15)
				)
				(justify left bottom)
				(hide yes)
			)
		)
		(property "Val" "0R"
			(at 68.58 106.68 0)
			(effects
				(font
					(size 1.27 1.27)
					(thickness 0.15)
				)
			)
		)
		(property "Tolerance" "~"
			(at 82.55 118.11 0)
			(effects
				(font
					(size 1.27 1.27)
				)
				(justify left bottom)
				(hide yes)
			)
		)
		(property "Current" "1A"
			(at 82.55 138.43 0)
			(effects
				(font
					(size 1.27 1.27)
					(thickness 0.15)
				)
				(justify left bottom)
				(hide yes)
			)
		)
		(pin "2"
		)
		(pin "1"
		)
		(instances
			(project "jetson-agx-thor-baseboard"
				(path ""
					(reference "R208")
					(unit 1)
				)
			)
		)
	)
	(symbol
		(lib_id "antmicroModules:Mech_M2_2280_H2.5mm")
		(at 86.36 203.2 0)
		(unit 1)
		(exclude_from_sim no)
		(in_bom no)
		(on_board yes)
		(dnp yes)
		(fields_autoplaced yes)
		(property "Reference" "A1"
			(at 97.79 205.105 0)
			(effects
				(font
					(size 1.27 1.27)
					(thickness 0.15)
				)
				(justify left)
			)
		)
		(property "Value" "Mech_M2_2280_H2.5mm"
			(at 97.79 207.645 0)
			(effects
				(font
					(size 1.27 1.27)
					(thickness 0.15)
				)
				(justify left)
			)
		)
		(property "Footprint" "antmicro-footprints:Mech_M2_2280_H2.5mm"
			(at 111.76 208.28 0)
			(effects
				(font
					(size 1.27 1.27)
					(thickness 0.15)
				)
				(justify left bottom)
				(hide yes)
			)
		)
		(property "Datasheet" ""
			(at 111.76 210.82 0)
			(effects
				(font
					(size 1.27 1.27)
					(thickness 0.15)
				)
				(justify left bottom)
				(hide yes)
			)
		)
		(property "Description" "Mechanical model for M2 2280 2.5mm module"
			(at 86.36 203.2 0)
			(effects
				(font
					(size 1.27 1.27)
				)
				(hide yes)
			)
		)
		(property "Manufacturer" ""
			(at 86.36 203.2 0)
			(effects
				(font
					(size 1.27 1.27)
				)
				(hide yes)
			)
		)
		(property "MPN" ""
			(at 86.36 203.2 0)
			(effects
				(font
					(size 1.27 1.27)
				)
			)
		)
		(property "Author" "Antmicro"
			(at 111.76 213.36 0)
			(effects
				(font
					(size 1.27 1.27)
					(thickness 0.15)
				)
				(justify left bottom)
				(hide yes)
			)
		)
		(property "License" "Apache-2.0"
			(at 111.76 215.9 0)
			(effects
				(font
					(size 1.27 1.27)
					(thickness 0.15)
				)
				(justify left bottom)
				(hide yes)
			)
		)
		(instances
			(project "jetson-agx-thor-baseboard"
				(path ""
					(reference "A1")
					(unit 1)
				)
			)
		)
	)
	(symbol
		(lib_id "antmicroLEDIndicationDiscrete:LED_G_0603_LTST-C190GKT")
		(at 132.08 154.94 90)
		(unit 1)
		(exclude_from_sim no)
		(in_bom yes)
		(on_board yes)
		(dnp no)
		(fields_autoplaced yes)
		(property "Reference" "D32"
			(at 134.62 151.13 90)
			(effects
				(font
					(size 1.27 1.27)
				)
				(justify right)
			)
		)
		(property "Value" "LED_G_0603_LTST-C190GKT"
			(at 139.7 132.08 0)
			(effects
				(font
					(size 1.27 1.27)
					(thickness 0.15)
				)
				(justify left bottom)
				(hide yes)
			)
		)
		(property "Footprint" "antmicro-footprints:LED_0603_1608Metric_G"
			(at 142.24 132.08 0)
			(effects
				(font
					(size 1.27 1.27)
					(thickness 0.15)
				)
				(justify left bottom)
				(hide yes)
			)
		)
		(property "Datasheet" "https://media.digikey.com/pdf/Data%20Sheets/Lite-On%20PDFs/LTST-C190GKT.pdf"
			(at 144.78 132.08 0)
			(effects
				(font
					(size 1.27 1.27)
					(thickness 0.15)
				)
				(justify left bottom)
				(hide yes)
			)
		)
		(property "Description" "LED, Green, SMD, 0603, 20 mA, 2.1 V, 569 nm"
			(at 132.08 154.94 0)
			(effects
				(font
					(size 1.27 1.27)
				)
				(hide yes)
			)
		)
		(property "MPN" "LTST-C190GKT"
			(at 147.32 132.08 0)
			(effects
				(font
					(size 1.27 1.27)
					(thickness 0.15)
				)
				(justify left bottom)
				(hide yes)
			)
		)
		(property "Manufacturer" "Lite-On"
			(at 149.86 132.08 0)
			(effects
				(font
					(size 1.27 1.27)
					(thickness 0.15)
				)
				(justify left bottom)
				(hide yes)
			)
		)
		(property "Author" "Antmicro"
			(at 152.4 132.08 0)
			(effects
				(font
					(size 1.27 1.27)
					(thickness 0.15)
				)
				(justify left bottom)
				(hide yes)
			)
		)
		(property "License" "Apache-2.0"
			(at 154.94 132.08 0)
			(effects
				(font
					(size 1.27 1.27)
					(thickness 0.15)
				)
				(justify left bottom)
				(hide yes)
			)
		)
		(property "Color" "Green"
			(at 134.62 153.67 90)
			(effects
				(font
					(size 1.27 1.27)
				)
				(justify right)
			)
		)
		(pin "1"
		)
		(pin "2"
		)
		(instances
			(project "jetson-agx-thor-baseboard"
				(path ""
					(reference "D32")
					(unit 1)
				)
			)
		)
	)
	(symbol
		(lib_id "antmicropower:+3V3")
		(at 93.98 261.62 0)
		(unit 1)
		(exclude_from_sim no)
		(in_bom yes)
		(on_board yes)
		(dnp no)
		(property "Reference" "#PWR0361"
			(at 93.98 265.43 0)
			(effects
				(font
					(size 1.27 1.27)
				)
				(justify left bottom)
				(hide yes)
			)
		)
		(property "Value" "+3V3"
			(at 93.345 257.81 0)
			(effects
				(font
					(size 1.27 1.27)
					(thickness 0.15)
				)
			)
		)
		(property "Footprint" ""
			(at 109.22 269.24 0)
			(effects
				(font
					(size 1.27 1.27)
					(thickness 0.15)
				)
				(justify left bottom)
				(hide yes)
			)
		)
		(property "Datasheet" ""
			(at 109.22 271.78 0)
			(effects
				(font
					(size 1.27 1.27)
					(thickness 0.15)
				)
				(justify left bottom)
				(hide yes)
			)
		)
		(property "Description" ""
			(at 93.98 261.62 0)
			(effects
				(font
					(size 1.27 1.27)
				)
				(hide yes)
			)
		)
		(property "Author" "Antmicro"
			(at 109.22 264.16 0)
			(effects
				(font
					(size 1.27 1.27)
					(thickness 0.15)
				)
				(justify left bottom)
				(hide yes)
			)
		)
		(property "License" "Apache-2.0"
			(at 109.22 266.7 0)
			(effects
				(font
					(size 1.27 1.27)
					(thickness 0.15)
				)
				(justify left bottom)
				(hide yes)
			)
		)
		(pin "1"
		)
		(instances
			(project "jetson-agx-thor-baseboard"
				(path ""
					(reference "#PWR0361")
					(unit 1)
				)
			)
		)
	)
	(symbol
		(lib_id "antmicroResistors0402:R_0R_0402")
		(at 62.23 102.87 0)
		(unit 1)
		(exclude_from_sim no)
		(in_bom yes)
		(on_board yes)
		(dnp no)
		(property "Reference" "R206"
			(at 59.69 101.6 0)
			(effects
				(font
					(size 1.27 1.27)
					(thickness 0.15)
				)
			)
		)
		(property "Value" "R_0R_0402"
			(at 82.55 115.57 0)
			(effects
				(font
					(size 1.27 1.27)
					(thickness 0.15)
				)
				(justify left bottom)
				(hide yes)
			)
		)
		(property "Footprint" "antmicro-footprints:R_0402_1005Metric"
			(at 82.55 118.11 0)
			(effects
				(font
					(size 1.27 1.27)
					(thickness 0.15)
				)
				(justify left bottom)
				(hide yes)
			)
		)
		(property "Datasheet" "https://industrial.panasonic.com/cdbs/www-data/pdf/RDA0000/AOA0000C301.pdf"
			(at 82.55 120.65 0)
			(effects
				(font
					(size 1.27 1.27)
					(thickness 0.15)
				)
				(justify left bottom)
				(hide yes)
			)
		)
		(property "Description" "SMD Chip Resistor, Jumper, 0 ohm, 100 mW, 0402 [1005 Metric], Thick Film, General Purpose"
			(at 62.23 102.87 0)
			(effects
				(font
					(size 1.27 1.27)
				)
				(hide yes)
			)
		)
		(property "MPN" "ERJ2GE0R00X"
			(at 82.55 123.19 0)
			(effects
				(font
					(size 1.27 1.27)
					(thickness 0.15)
				)
				(justify left bottom)
				(hide yes)
			)
		)
		(property "Manufacturer" "Panasonic"
			(at 82.55 125.73 0)
			(effects
				(font
					(size 1.27 1.27)
					(thickness 0.15)
				)
				(justify left bottom)
				(hide yes)
			)
		)
		(property "License" "Apache-2.0"
			(at 82.55 128.27 0)
			(effects
				(font
					(size 1.27 1.27)
					(thickness 0.15)
				)
				(justify left bottom)
				(hide yes)
			)
		)
		(property "Author" "Antmicro"
			(at 82.55 130.81 0)
			(effects
				(font
					(size 1.27 1.27)
					(thickness 0.15)
				)
				(justify left bottom)
				(hide yes)
			)
		)
		(property "Val" "0R"
			(at 68.58 101.6 0)
			(effects
				(font
					(size 1.27 1.27)
					(thickness 0.15)
				)
			)
		)
		(property "Tolerance" "~"
			(at 82.55 113.03 0)
			(effects
				(font
					(size 1.27 1.27)
				)
				(justify left bottom)
				(hide yes)
			)
		)
		(property "Current" "1A"
			(at 82.55 133.35 0)
			(effects
				(font
					(size 1.27 1.27)
					(thickness 0.15)
				)
				(justify left bottom)
				(hide yes)
			)
		)
		(pin "2"
		)
		(pin "1"
		)
		(instances
			(project "jetson-agx-thor-baseboard"
				(path ""
					(reference "R206")
					(unit 1)
				)
			)
		)
	)
	(symbol
		(lib_id "antmicroCapacitors0603:C_22u_16V_0603")
		(at 147.32 100.33 90)
		(mirror x)
		(unit 1)
		(exclude_from_sim no)
		(in_bom yes)
		(on_board yes)
		(dnp no)
		(fields_autoplaced yes)
		(property "Reference" "C191"
			(at 149.86 101.6063 90)
			(effects
				(font
					(size 1.27 1.27)
				)
				(justify right)
			)
		)
		(property "Value" "C_22u_16V_0603"
			(at 157.48 120.65 0)
			(effects
				(font
					(size 1.27 1.27)
					(thickness 0.15)
				)
				(justify left bottom)
				(hide yes)
			)
		)
		(property "Footprint" "antmicro-footprints:C_0603_1608Metric_EIA"
			(at 160.02 120.65 0)
			(effects
				(font
					(size 1.27 1.27)
					(thickness 0.15)
				)
				(justify left bottom)
				(hide yes)
			)
		)
		(property "Datasheet" "https://product.samsungsem.com/mlcc/CL10A226MO7JZN.do"
			(at 162.56 120.65 0)
			(effects
				(font
					(size 1.27 1.27)
					(thickness 0.15)
				)
				(justify left bottom)
				(hide yes)
			)
		)
		(property "Description" "SMD Multilayer Ceramic Capacitor"
			(at 147.32 100.33 0)
			(effects
				(font
					(size 1.27 1.27)
				)
				(hide yes)
			)
		)
		(property "Manufacturer" "Samsung Electro-Mechanics"
			(at 167.64 120.65 0)
			(effects
				(font
					(size 1.27 1.27)
					(thickness 0.15)
				)
				(justify left bottom)
				(hide yes)
			)
		)
		(property "MPN" "CL10A226MO7JZNC"
			(at 165.1 120.65 0)
			(effects
				(font
					(size 1.27 1.27)
					(thickness 0.15)
				)
				(justify left bottom)
				(hide yes)
			)
		)
		(property "Val" "22u"
			(at 149.86 104.1463 90)
			(effects
				(font
					(size 1.27 1.27)
					(thickness 0.15)
				)
				(justify right)
			)
		)
		(property "License" "Apache-2.0"
			(at 170.18 120.65 0)
			(effects
				(font
					(size 1.27 1.27)
					(thickness 0.15)
				)
				(justify left bottom)
				(hide yes)
			)
		)
		(property "Author" "Antmicro"
			(at 172.72 120.65 0)
			(effects
				(font
					(size 1.27 1.27)
					(thickness 0.15)
				)
				(justify left bottom)
				(hide yes)
			)
		)
		(property "Voltage" "16V"
			(at 175.26 120.65 0)
			(effects
				(font
					(size 1.27 1.27)
				)
				(justify left bottom)
				(hide yes)
			)
		)
		(property "Dielectric" "template_dielectric"
			(at 177.8 120.65 0)
			(effects
				(font
					(size 1.27 1.27)
				)
				(justify left bottom)
				(hide yes)
			)
		)
		(pin "1"
		)
		(pin "2"
		)
		(instances
			(project "jetson-agx-thor-baseboard"
				(path ""
					(reference "C191")
					(unit 1)
				)
			)
		)
	)
	(symbol
		(lib_id "antmicroResistors0603:R_0R_22.4A_0603")
		(at 167.64 95.25 90)
		(unit 1)
		(exclude_from_sim no)
		(in_bom yes)
		(on_board yes)
		(dnp no)
		(property "Reference" "R213"
			(at 170.18 90.17 90)
			(effects
				(font
					(size 1.27 1.27)
				)
				(justify right)
			)
		)
		(property "Value" "R_0R_22.4A_0603"
			(at 170.18 91.44 90)
			(effects
				(font
					(size 1.27 1.27)
					(thickness 0.15)
				)
				(justify right)
				(hide yes)
			)
		)
		(property "Footprint" "antmicro-footprints:R_0603_1608Metric"
			(at 177.8 80.01 0)
			(effects
				(font
					(size 1.27 1.27)
					(thickness 0.15)
				)
				(justify left bottom)
				(hide yes)
			)
		)
		(property "Datasheet" "https://fscdn.rohm.com/en/products/databook/datasheet/passive/resistor/chip_resistor/pmr-jpw-e.pdf"
			(at 180.34 80.01 0)
			(effects
				(font
					(size 1.27 1.27)
					(thickness 0.15)
				)
				(justify left bottom)
				(hide yes)
			)
		)
		(property "Description" "SMD Chip Resistor"
			(at 167.64 95.25 0)
			(effects
				(font
					(size 1.27 1.27)
				)
				(hide yes)
			)
		)
		(property "Manufacturer" "ROHM Semiconductor"
			(at 185.42 80.01 0)
			(effects
				(font
					(size 1.27 1.27)
					(thickness 0.15)
				)
				(justify left bottom)
				(hide yes)
			)
		)
		(property "MPN" "PMR03EZPJ000"
			(at 182.88 80.01 0)
			(effects
				(font
					(size 1.27 1.27)
					(thickness 0.15)
				)
				(justify left bottom)
				(hide yes)
			)
		)
		(property "Val" "0R"
			(at 170.18 92.71 90)
			(effects
				(font
					(size 1.27 1.27)
					(thickness 0.15)
				)
				(justify right)
			)
		)
		(property "Author" "Antmicro"
			(at 190.5 80.01 0)
			(effects
				(font
					(size 1.27 1.27)
					(thickness 0.15)
				)
				(justify left bottom)
				(hide yes)
			)
		)
		(property "License" "Apache-2.0"
			(at 193.04 80.01 0)
			(effects
				(font
					(size 1.27 1.27)
					(thickness 0.15)
				)
				(justify left bottom)
				(hide yes)
			)
		)
		(property "Max. Curr." "22.4A"
			(at 170.18 95.25 90)
			(effects
				(font
					(size 1.27 1.27)
					(thickness 0.15)
				)
				(justify right)
			)
		)
		(property "Tolerance" "template_tolerance"
			(at 177.8 74.93 0)
			(effects
				(font
					(size 1.27 1.27)
				)
				(justify left bottom)
				(hide yes)
			)
		)
		(pin "1"
		)
		(pin "2"
		)
		(instances
			(project "jetson-agx-thor-baseboard"
				(path ""
					(reference "R213")
					(unit 1)
				)
			)
		)
	)
	(symbol
		(lib_id "antmicropower:PWR_FLAG")
		(at 132.08 97.79 0)
		(unit 1)
		(exclude_from_sim no)
		(in_bom yes)
		(on_board yes)
		(dnp no)
		(property "Reference" "#FLG010"
			(at 132.08 95.885 0)
			(effects
				(font
					(size 1.27 1.27)
				)
				(hide yes)
			)
		)
		(property "Value" "PWR_FLAG"
			(at 132.08 93.98 0)
			(effects
				(font
					(size 1.27 1.27)
				)
			)
		)
		(property "Footprint" ""
			(at 132.08 97.79 0)
			(effects
				(font
					(size 1.27 1.27)
				)
				(hide yes)
			)
		)
		(property "Datasheet" ""
			(at 132.08 97.79 0)
			(effects
				(font
					(size 1.27 1.27)
				)
				(hide yes)
			)
		)
		(property "Description" ""
			(at 132.08 97.79 0)
			(effects
				(font
					(size 1.27 1.27)
				)
				(hide yes)
			)
		)
		(pin "1"
		)
		(instances
			(project "jetson-agx-thor-baseboard"
				(path ""
					(reference "#FLG010")
					(unit 1)
				)
			)
		)
	)
	(symbol
		(lib_id "antmicroResistors0402:R_47k_0402")
		(at 255.27 92.71 90)
		(unit 1)
		(exclude_from_sim no)
		(in_bom yes)
		(on_board yes)
		(dnp no)
		(property "Reference" "R220"
			(at 256.54 88.9 90)
			(effects
				(font
					(size 1.27 1.27)
					(thickness 0.15)
				)
				(justify right)
			)
		)
		(property "Value" "R_47k_0402"
			(at 267.97 72.39 0)
			(effects
				(font
					(size 1.27 1.27)
					(thickness 0.15)
				)
				(justify left bottom)
				(hide yes)
			)
		)
		(property "Footprint" "antmicro-footprints:R_0402_1005Metric"
			(at 270.51 72.39 0)
			(effects
				(font
					(size 1.27 1.27)
					(thickness 0.15)
				)
				(justify left bottom)
				(hide yes)
			)
		)
		(property "Datasheet" "https://www.bourns.com/docs/product-datasheets/cr.pdf"
			(at 273.05 72.39 0)
			(effects
				(font
					(size 1.27 1.27)
					(thickness 0.15)
				)
				(justify left bottom)
				(hide yes)
			)
		)
		(property "Description" "SMD Chip Resistor, 47 kohm, ± 1%, 62.5 mW, 0402 [1005 Metric], Thick Film, General Purpose"
			(at 285.75 72.39 0)
			(effects
				(font
					(size 1.27 1.27)
				)
				(justify left bottom)
				(hide yes)
			)
		)
		(property "MPN" "CR0402-FX-4702GLF"
			(at 275.59 72.39 0)
			(effects
				(font
					(size 1.27 1.27)
					(thickness 0.15)
				)
				(justify left bottom)
				(hide yes)
			)
		)
		(property "Manufacturer" "Bourns"
			(at 278.13 72.39 0)
			(effects
				(font
					(size 1.27 1.27)
					(thickness 0.15)
				)
				(justify left bottom)
				(hide yes)
			)
		)
		(property "License" "Apache-2.0"
			(at 280.67 72.39 0)
			(effects
				(font
					(size 1.27 1.27)
					(thickness 0.15)
				)
				(justify left bottom)
				(hide yes)
			)
		)
		(property "Author" "Antmicro"
			(at 283.21 72.39 0)
			(effects
				(font
					(size 1.27 1.27)
					(thickness 0.15)
				)
				(justify left bottom)
				(hide yes)
			)
		)
		(property "Val" "47k"
			(at 256.54 91.44 90)
			(effects
				(font
					(size 1.27 1.27)
					(thickness 0.15)
				)
				(justify right)
			)
		)
		(property "Tolerance" "1%"
			(at 265.43 72.39 0)
			(effects
				(font
					(size 1.27 1.27)
				)
				(justify left bottom)
				(hide yes)
			)
		)
		(pin "2"
		)
		(pin "1"
		)
		(instances
			(project "jetson-agx-thor-baseboard"
				(path ""
					(reference "R220")
					(unit 1)
				)
			)
		)
	)
	(symbol
		(lib_id "antmicroCapacitors0603:C_22u_16V_0603")
		(at 137.16 100.33 90)
		(mirror x)
		(unit 1)
		(exclude_from_sim no)
		(in_bom yes)
		(on_board yes)
		(dnp no)
		(fields_autoplaced yes)
		(property "Reference" "C190"
			(at 139.7 101.6063 90)
			(effects
				(font
					(size 1.27 1.27)
				)
				(justify right)
			)
		)
		(property "Value" "C_22u_16V_0603"
			(at 147.32 120.65 0)
			(effects
				(font
					(size 1.27 1.27)
					(thickness 0.15)
				)
				(justify left bottom)
				(hide yes)
			)
		)
		(property "Footprint" "antmicro-footprints:C_0603_1608Metric_EIA"
			(at 149.86 120.65 0)
			(effects
				(font
					(size 1.27 1.27)
					(thickness 0.15)
				)
				(justify left bottom)
				(hide yes)
			)
		)
		(property "Datasheet" "https://product.samsungsem.com/mlcc/CL10A226MO7JZN.do"
			(at 152.4 120.65 0)
			(effects
				(font
					(size 1.27 1.27)
					(thickness 0.15)
				)
				(justify left bottom)
				(hide yes)
			)
		)
		(property "Description" "SMD Multilayer Ceramic Capacitor"
			(at 137.16 100.33 0)
			(effects
				(font
					(size 1.27 1.27)
				)
				(hide yes)
			)
		)
		(property "Manufacturer" "Samsung Electro-Mechanics"
			(at 157.48 120.65 0)
			(effects
				(font
					(size 1.27 1.27)
					(thickness 0.15)
				)
				(justify left bottom)
				(hide yes)
			)
		)
		(property "MPN" "CL10A226MO7JZNC"
			(at 154.94 120.65 0)
			(effects
				(font
					(size 1.27 1.27)
					(thickness 0.15)
				)
				(justify left bottom)
				(hide yes)
			)
		)
		(property "Val" "22u"
			(at 139.7 104.1463 90)
			(effects
				(font
					(size 1.27 1.27)
					(thickness 0.15)
				)
				(justify right)
			)
		)
		(property "License" "Apache-2.0"
			(at 160.02 120.65 0)
			(effects
				(font
					(size 1.27 1.27)
					(thickness 0.15)
				)
				(justify left bottom)
				(hide yes)
			)
		)
		(property "Author" "Antmicro"
			(at 162.56 120.65 0)
			(effects
				(font
					(size 1.27 1.27)
					(thickness 0.15)
				)
				(justify left bottom)
				(hide yes)
			)
		)
		(property "Voltage" "16V"
			(at 165.1 120.65 0)
			(effects
				(font
					(size 1.27 1.27)
				)
				(justify left bottom)
				(hide yes)
			)
		)
		(property "Dielectric" "template_dielectric"
			(at 167.64 120.65 0)
			(effects
				(font
					(size 1.27 1.27)
				)
				(justify left bottom)
				(hide yes)
			)
		)
		(pin "1"
		)
		(pin "2"
		)
		(instances
			(project "jetson-agx-thor-baseboard"
				(path ""
					(reference "C190")
					(unit 1)
				)
			)
		)
	)
	(symbol
		(lib_id "antmicroTestPoints:TP_0.75mm_SMD")
		(at 312.42 119.38 90)
		(unit 1)
		(exclude_from_sim no)
		(in_bom no)
		(on_board yes)
		(dnp no)
		(property "Reference" "TP39"
			(at 315.214 113.538 90)
			(effects
				(font
					(size 1.27 1.27)
				)
				(justify left bottom)
			)
		)
		(property "Value" "TP_0.75mm_SMD"
			(at 316.23 109.22 0)
			(effects
				(font
					(size 1.27 1.27)
					(thickness 0.15)
				)
				(justify left bottom)
				(hide yes)
			)
		)
		(property "Footprint" "antmicro-footprints:TP_SMD_0.75mm"
			(at 318.77 109.22 0)
			(effects
				(font
					(size 1.27 1.27)
					(thickness 0.15)
				)
				(justify left bottom)
				(hide yes)
			)
		)
		(property "Datasheet" ""
			(at 325.12 101.6 0)
			(effects
				(font
					(size 1.27 1.27)
					(thickness 0.15)
				)
				(justify left bottom)
				(hide yes)
			)
		)
		(property "Description" "SMT test point"
			(at 312.42 119.38 0)
			(effects
				(font
					(size 1.27 1.27)
				)
				(hide yes)
			)
		)
		(property "MPN" ""
			(at 323.85 108.585 0)
			(effects
				(font
					(size 1.27 1.27)
					(thickness 0.15)
				)
				(justify left bottom)
				(hide yes)
			)
		)
		(property "Manufacturer" ""
			(at 318.77 108.585 0)
			(effects
				(font
					(size 1.27 1.27)
					(thickness 0.15)
				)
				(justify left bottom)
				(hide yes)
			)
		)
		(property "Author" "Antmicro"
			(at 321.31 109.22 0)
			(effects
				(font
					(size 1.27 1.27)
					(thickness 0.15)
				)
				(justify left bottom)
				(hide yes)
			)
		)
		(property "License" "Apache-2.0"
			(at 323.85 109.22 0)
			(effects
				(font
					(size 1.27 1.27)
					(thickness 0.15)
				)
				(justify left bottom)
				(hide yes)
			)
		)
		(pin "1"
		)
		(instances
			(project "jetson-agx-thor-baseboard"
				(path ""
					(reference "TP39")
					(unit 1)
				)
			)
		)
	)
	(symbol
		(lib_id "antmicroResistors0402:R_0R_0402")
		(at 62.23 105.41 0)
		(unit 1)
		(exclude_from_sim no)
		(in_bom yes)
		(on_board yes)
		(dnp no)
		(property "Reference" "R207"
			(at 59.69 104.14 0)
			(effects
				(font
					(size 1.27 1.27)
					(thickness 0.15)
				)
			)
		)
		(property "Value" "R_0R_0402"
			(at 82.55 118.11 0)
			(effects
				(font
					(size 1.27 1.27)
					(thickness 0.15)
				)
				(justify left bottom)
				(hide yes)
			)
		)
		(property "Footprint" "antmicro-footprints:R_0402_1005Metric"
			(at 82.55 120.65 0)
			(effects
				(font
					(size 1.27 1.27)
					(thickness 0.15)
				)
				(justify left bottom)
				(hide yes)
			)
		)
		(property "Datasheet" "https://industrial.panasonic.com/cdbs/www-data/pdf/RDA0000/AOA0000C301.pdf"
			(at 82.55 123.19 0)
			(effects
				(font
					(size 1.27 1.27)
					(thickness 0.15)
				)
				(justify left bottom)
				(hide yes)
			)
		)
		(property "Description" "SMD Chip Resistor, Jumper, 0 ohm, 100 mW, 0402 [1005 Metric], Thick Film, General Purpose"
			(at 62.23 105.41 0)
			(effects
				(font
					(size 1.27 1.27)
				)
				(hide yes)
			)
		)
		(property "MPN" "ERJ2GE0R00X"
			(at 82.55 125.73 0)
			(effects
				(font
					(size 1.27 1.27)
					(thickness 0.15)
				)
				(justify left bottom)
				(hide yes)
			)
		)
		(property "Manufacturer" "Panasonic"
			(at 82.55 128.27 0)
			(effects
				(font
					(size 1.27 1.27)
					(thickness 0.15)
				)
				(justify left bottom)
				(hide yes)
			)
		)
		(property "License" "Apache-2.0"
			(at 82.55 130.81 0)
			(effects
				(font
					(size 1.27 1.27)
					(thickness 0.15)
				)
				(justify left bottom)
				(hide yes)
			)
		)
		(property "Author" "Antmicro"
			(at 82.55 133.35 0)
			(effects
				(font
					(size 1.27 1.27)
					(thickness 0.15)
				)
				(justify left bottom)
				(hide yes)
			)
		)
		(property "Val" "0R"
			(at 68.58 104.14 0)
			(effects
				(font
					(size 1.27 1.27)
					(thickness 0.15)
				)
			)
		)
		(property "Tolerance" "~"
			(at 82.55 115.57 0)
			(effects
				(font
					(size 1.27 1.27)
				)
				(justify left bottom)
				(hide yes)
			)
		)
		(property "Current" "1A"
			(at 82.55 135.89 0)
			(effects
				(font
					(size 1.27 1.27)
					(thickness 0.15)
				)
				(justify left bottom)
				(hide yes)
			)
		)
		(pin "2"
		)
		(pin "1"
		)
		(instances
			(project "jetson-agx-thor-baseboard"
				(path ""
					(reference "R207")
					(unit 1)
				)
			)
		)
	)
	(symbol
		(lib_id "antmicroResistors0402:R_0R_0402")
		(at 153.67 115.57 0)
		(unit 1)
		(exclude_from_sim no)
		(in_bom yes)
		(on_board yes)
		(dnp no)
		(property "Reference" "R212"
			(at 151.384 114.3 0)
			(effects
				(font
					(size 1.27 1.27)
					(thickness 0.15)
				)
			)
		)
		(property "Value" "R_0R_0402"
			(at 173.99 128.27 0)
			(effects
				(font
					(size 1.27 1.27)
					(thickness 0.15)
				)
				(justify left bottom)
				(hide yes)
			)
		)
		(property "Footprint" "antmicro-footprints:R_0402_1005Metric"
			(at 173.99 130.81 0)
			(effects
				(font
					(size 1.27 1.27)
					(thickness 0.15)
				)
				(justify left bottom)
				(hide yes)
			)
		)
		(property "Datasheet" "https://industrial.panasonic.com/cdbs/www-data/pdf/RDA0000/AOA0000C301.pdf"
			(at 173.99 133.35 0)
			(effects
				(font
					(size 1.27 1.27)
					(thickness 0.15)
				)
				(justify left bottom)
				(hide yes)
			)
		)
		(property "Description" "SMD Chip Resistor, Jumper, 0 ohm, 100 mW, 0402 [1005 Metric], Thick Film, General Purpose"
			(at 153.67 115.57 0)
			(effects
				(font
					(size 1.27 1.27)
				)
				(hide yes)
			)
		)
		(property "MPN" "ERJ2GE0R00X"
			(at 173.99 135.89 0)
			(effects
				(font
					(size 1.27 1.27)
					(thickness 0.15)
				)
				(justify left bottom)
				(hide yes)
			)
		)
		(property "Manufacturer" "Panasonic"
			(at 173.99 138.43 0)
			(effects
				(font
					(size 1.27 1.27)
					(thickness 0.15)
				)
				(justify left bottom)
				(hide yes)
			)
		)
		(property "License" "Apache-2.0"
			(at 173.99 140.97 0)
			(effects
				(font
					(size 1.27 1.27)
					(thickness 0.15)
				)
				(justify left bottom)
				(hide yes)
			)
		)
		(property "Val" "0R"
			(at 160.02 114.3 0)
			(effects
				(font
					(size 1.27 1.27)
					(thickness 0.15)
				)
			)
		)
		(property "Tolerance" "~"
			(at 173.99 125.73 0)
			(effects
				(font
					(size 1.27 1.27)
				)
				(justify left bottom)
				(hide yes)
			)
		)
		(property "Current" "1A"
			(at 156.21 111.76 0)
			(effects
				(font
					(size 1.27 1.27)
					(thickness 0.15)
				)
				(hide yes)
			)
		)
		(property "Author" "Antmicro"
			(at 173.99 143.51 0)
			(effects
				(font
					(size 1.27 1.27)
					(thickness 0.15)
				)
				(justify left bottom)
				(hide yes)
			)
		)
		(property "Public" "False"
			(at 173.99 146.05 0)
			(effects
				(font
					(size 1.27 1.27)
				)
				(justify left bottom)
				(hide yes)
			)
		)
		(pin "1"
		)
		(pin "2"
		)
		(instances
			(project "jetson-agx-thor-baseboard"
				(path ""
					(reference "R212")
					(unit 1)
				)
			)
		)
	)
	(symbol
		(lib_id "antmicroCapacitors0603:C_22u_16V_0603")
		(at 309.88 93.98 90)
		(unit 1)
		(exclude_from_sim no)
		(in_bom yes)
		(on_board yes)
		(dnp no)
		(fields_autoplaced yes)
		(property "Reference" "C74"
			(at 312.42 90.1636 90)
			(effects
				(font
					(size 1.27 1.27)
					(thickness 0.15)
				)
				(justify right)
			)
		)
		(property "Value" "C_22u_16V_0603"
			(at 320.04 73.66 0)
			(effects
				(font
					(size 1.27 1.27)
					(thickness 0.15)
				)
				(justify left bottom)
				(hide yes)
			)
		)
		(property "Footprint" "antmicro-footprints:C_0603_1608Metric_EIA"
			(at 322.58 73.66 0)
			(effects
				(font
					(size 1.27 1.27)
					(thickness 0.15)
				)
				(justify left bottom)
				(hide yes)
			)
		)
		(property "Datasheet" "https://product.samsungsem.com/mlcc/CL10A226MO7JZN.do"
			(at 325.12 73.66 0)
			(effects
				(font
					(size 1.27 1.27)
					(thickness 0.15)
				)
				(justify left bottom)
				(hide yes)
			)
		)
		(property "Description" "SMD Multilayer Ceramic Capacitor"
			(at 309.88 93.98 0)
			(effects
				(font
					(size 1.27 1.27)
				)
				(hide yes)
			)
		)
		(property "MPN" "CL10A226MO7JZNC"
			(at 327.66 73.66 0)
			(effects
				(font
					(size 1.27 1.27)
					(thickness 0.15)
				)
				(justify left bottom)
				(hide yes)
			)
		)
		(property "Manufacturer" "Samsung Electro-Mechanics"
			(at 330.2 73.66 0)
			(effects
				(font
					(size 1.27 1.27)
					(thickness 0.15)
				)
				(justify left bottom)
				(hide yes)
			)
		)
		(property "License" "Apache-2.0"
			(at 332.74 73.66 0)
			(effects
				(font
					(size 1.27 1.27)
					(thickness 0.15)
				)
				(justify left bottom)
				(hide yes)
			)
		)
		(property "Author" "Antmicro"
			(at 335.28 73.66 0)
			(effects
				(font
					(size 1.27 1.27)
					(thickness 0.15)
				)
				(justify left bottom)
				(hide yes)
			)
		)
		(property "Val" "22u"
			(at 312.42 92.7036 90)
			(effects
				(font
					(size 1.27 1.27)
					(thickness 0.15)
				)
				(justify right)
			)
		)
		(property "Voltage" "16V"
			(at 337.82 73.66 0)
			(effects
				(font
					(size 1.27 1.27)
				)
				(justify left bottom)
				(hide yes)
			)
		)
		(property "Dielectric" ""
			(at 340.36 73.66 0)
			(effects
				(font
					(size 1.27 1.27)
				)
				(justify left bottom)
				(hide yes)
			)
		)
		(pin "2"
		)
		(pin "1"
		)
		(instances
			(project "jetson-agx-thor-baseboard"
				(path ""
					(reference "C74")
					(unit 1)
				)
			)
		)
	)
	(symbol
		(lib_id "antmicroResistors0402:R_0R_0402")
		(at 224.79 99.06 0)
		(unit 1)
		(exclude_from_sim no)
		(in_bom yes)
		(on_board yes)
		(dnp no)
		(property "Reference" "R216"
			(at 222.504 97.79 0)
			(effects
				(font
					(size 1.27 1.27)
					(thickness 0.15)
				)
			)
		)
		(property "Value" "R_0R_0402"
			(at 245.11 111.76 0)
			(effects
				(font
					(size 1.27 1.27)
					(thickness 0.15)
				)
				(justify left bottom)
				(hide yes)
			)
		)
		(property "Footprint" "antmicro-footprints:R_0402_1005Metric"
			(at 245.11 114.3 0)
			(effects
				(font
					(size 1.27 1.27)
					(thickness 0.15)
				)
				(justify left bottom)
				(hide yes)
			)
		)
		(property "Datasheet" "https://industrial.panasonic.com/cdbs/www-data/pdf/RDA0000/AOA0000C301.pdf"
			(at 245.11 116.84 0)
			(effects
				(font
					(size 1.27 1.27)
					(thickness 0.15)
				)
				(justify left bottom)
				(hide yes)
			)
		)
		(property "Description" "SMD Chip Resistor, Jumper, 0 ohm, 100 mW, 0402 [1005 Metric], Thick Film, General Purpose"
			(at 224.79 99.06 0)
			(effects
				(font
					(size 1.27 1.27)
				)
				(hide yes)
			)
		)
		(property "MPN" "ERJ2GE0R00X"
			(at 245.11 119.38 0)
			(effects
				(font
					(size 1.27 1.27)
					(thickness 0.15)
				)
				(justify left bottom)
				(hide yes)
			)
		)
		(property "Manufacturer" "Panasonic"
			(at 245.11 121.92 0)
			(effects
				(font
					(size 1.27 1.27)
					(thickness 0.15)
				)
				(justify left bottom)
				(hide yes)
			)
		)
		(property "License" "Apache-2.0"
			(at 245.11 124.46 0)
			(effects
				(font
					(size 1.27 1.27)
					(thickness 0.15)
				)
				(justify left bottom)
				(hide yes)
			)
		)
		(property "Author" "Antmicro"
			(at 245.11 127 0)
			(effects
				(font
					(size 1.27 1.27)
					(thickness 0.15)
				)
				(justify left bottom)
				(hide yes)
			)
		)
		(property "Val" "0R"
			(at 231.14 97.79 0)
			(effects
				(font
					(size 1.27 1.27)
					(thickness 0.15)
				)
			)
		)
		(property "Tolerance" "~"
			(at 245.11 109.22 0)
			(effects
				(font
					(size 1.27 1.27)
				)
				(justify left bottom)
				(hide yes)
			)
		)
		(property "Current" "1A"
			(at 245.11 129.54 0)
			(effects
				(font
					(size 1.27 1.27)
					(thickness 0.15)
				)
				(justify left bottom)
				(hide yes)
			)
		)
		(pin "2"
		)
		(pin "1"
		)
		(instances
			(project "jetson-agx-thor-baseboard"
				(path ""
					(reference "R216")
					(unit 1)
				)
			)
		)
	)
	(symbol
		(lib_id "antmicropower:GND")
		(at 157.48 105.41 0)
		(unit 1)
		(exclude_from_sim no)
		(in_bom yes)
		(on_board yes)
		(dnp no)
		(property "Reference" "#PWR0370"
			(at 157.48 111.76 0)
			(effects
				(font
					(size 1.27 1.27)
				)
				(justify left bottom)
				(hide yes)
			)
		)
		(property "Value" "GND"
			(at 155.575 109.855 0)
			(effects
				(font
					(size 1.27 1.27)
					(thickness 0.15)
				)
				(justify left bottom)
			)
		)
		(property "Footprint" ""
			(at 166.37 113.03 0)
			(effects
				(font
					(size 1.27 1.27)
					(thickness 0.15)
				)
				(justify left bottom)
				(hide yes)
			)
		)
		(property "Datasheet" ""
			(at 166.37 118.11 0)
			(effects
				(font
					(size 1.27 1.27)
					(thickness 0.15)
				)
				(justify left bottom)
				(hide yes)
			)
		)
		(property "Description" ""
			(at 157.48 105.41 0)
			(effects
				(font
					(size 1.27 1.27)
				)
				(hide yes)
			)
		)
		(property "Author" "Antmicro"
			(at 166.37 113.03 0)
			(effects
				(font
					(size 1.27 1.27)
					(thickness 0.15)
				)
				(justify left bottom)
				(hide yes)
			)
		)
		(property "License" "Apache-2.0"
			(at 166.37 115.57 0)
			(effects
				(font
					(size 1.27 1.27)
					(thickness 0.15)
				)
				(justify left bottom)
				(hide yes)
			)
		)
		(pin "1"
		)
		(instances
			(project "jetson-agx-thor-baseboard"
				(path ""
					(reference "#PWR0370")
					(unit 1)
				)
			)
		)
	)
	(symbol
		(lib_id "antmicropower:GND")
		(at 285.75 236.22 0)
		(unit 1)
		(exclude_from_sim no)
		(in_bom yes)
		(on_board yes)
		(dnp no)
		(property "Reference" "#PWR0374"
			(at 285.75 242.57 0)
			(effects
				(font
					(size 1.27 1.27)
				)
				(justify left bottom)
				(hide yes)
			)
		)
		(property "Value" "GND"
			(at 283.845 240.03 0)
			(effects
				(font
					(size 1.27 1.27)
					(thickness 0.15)
				)
				(justify left)
			)
		)
		(property "Footprint" ""
			(at 294.64 243.84 0)
			(effects
				(font
					(size 1.27 1.27)
					(thickness 0.15)
				)
				(justify left bottom)
				(hide yes)
			)
		)
		(property "Datasheet" ""
			(at 294.64 248.92 0)
			(effects
				(font
					(size 1.27 1.27)
					(thickness 0.15)
				)
				(justify left bottom)
				(hide yes)
			)
		)
		(property "Description" ""
			(at 285.75 236.22 0)
			(effects
				(font
					(size 1.27 1.27)
				)
				(hide yes)
			)
		)
		(property "Author" "Antmicro"
			(at 294.64 243.84 0)
			(effects
				(font
					(size 1.27 1.27)
					(thickness 0.15)
				)
				(justify left bottom)
				(hide yes)
			)
		)
		(property "License" "Apache-2.0"
			(at 294.64 246.38 0)
			(effects
				(font
					(size 1.27 1.27)
					(thickness 0.15)
				)
				(justify left bottom)
				(hide yes)
			)
		)
		(pin "1"
		)
		(instances
			(project "jetson-agx-thor-baseboard"
				(path ""
					(reference "#PWR0374")
					(unit 1)
				)
			)
		)
	)
	(symbol
		(lib_id "antmicropower:+3V3")
		(at 167.64 88.9 0)
		(unit 1)
		(exclude_from_sim no)
		(in_bom yes)
		(on_board yes)
		(dnp no)
		(property "Reference" "#PWR0371"
			(at 167.64 92.71 0)
			(effects
				(font
					(size 1.27 1.27)
				)
				(justify left bottom)
				(hide yes)
			)
		)
		(property "Value" "+3V3"
			(at 164.465 85.09 0)
			(effects
				(font
					(size 1.27 1.27)
					(thickness 0.15)
				)
				(justify left)
			)
		)
		(property "Footprint" ""
			(at 182.88 96.52 0)
			(effects
				(font
					(size 1.27 1.27)
					(thickness 0.15)
				)
				(justify left bottom)
				(hide yes)
			)
		)
		(property "Datasheet" ""
			(at 182.88 99.06 0)
			(effects
				(font
					(size 1.27 1.27)
					(thickness 0.15)
				)
				(justify left bottom)
				(hide yes)
			)
		)
		(property "Description" ""
			(at 167.64 88.9 0)
			(effects
				(font
					(size 1.27 1.27)
				)
				(hide yes)
			)
		)
		(property "Author" "Antmicro"
			(at 182.88 91.44 0)
			(effects
				(font
					(size 1.27 1.27)
					(thickness 0.15)
				)
				(justify left bottom)
				(hide yes)
			)
		)
		(property "License" "Apache-2.0"
			(at 182.88 93.98 0)
			(effects
				(font
					(size 1.27 1.27)
					(thickness 0.15)
				)
				(justify left bottom)
				(hide yes)
			)
		)
		(pin "1"
		)
		(instances
			(project "jetson-agx-thor-baseboard"
				(path ""
					(reference "#PWR0371")
					(unit 1)
				)
			)
		)
	)
	(symbol
		(lib_id "antmicroModules:Mech_M2_2242_H2.5mm")
		(at 285.75 224.79 180)
		(unit 1)
		(exclude_from_sim no)
		(in_bom no)
		(on_board yes)
		(dnp yes)
		(property "Reference" "A2"
			(at 280.67 213.995 0)
			(effects
				(font
					(size 1.27 1.27)
					(thickness 0.15)
				)
			)
		)
		(property "Value" "Mech_M2_2242_H2.5mm"
			(at 280.67 216.535 0)
			(effects
				(font
					(size 1.27 1.27)
					(thickness 0.15)
				)
			)
		)
		(property "Footprint" "antmicro-footprints:Mech_M2_2242_H2.5mm"
			(at 260.35 219.71 0)
			(effects
				(font
					(size 1.27 1.27)
					(thickness 0.15)
				)
				(justify left bottom)
				(hide yes)
			)
		)
		(property "Datasheet" ""
			(at 260.35 217.17 0)
			(effects
				(font
					(size 1.27 1.27)
					(thickness 0.15)
				)
				(justify left bottom)
				(hide yes)
			)
		)
		(property "Description" "Mechanical model for M2 2242 2.5mm module"
			(at 285.75 224.79 0)
			(effects
				(font
					(size 1.27 1.27)
				)
				(hide yes)
			)
		)
		(property "MPN" ""
			(at 285.75 224.79 0)
			(effects
				(font
					(size 1.27 1.27)
				)
			)
		)
		(property "Manufacturer" ""
			(at 285.75 224.79 0)
			(effects
				(font
					(size 1.27 1.27)
				)
				(hide yes)
			)
		)
		(property "Author" "Antmicro"
			(at 260.35 214.63 0)
			(effects
				(font
					(size 1.27 1.27)
					(thickness 0.15)
				)
				(justify left bottom)
				(hide yes)
			)
		)
		(property "License" "Apache-2.0"
			(at 260.35 212.09 0)
			(effects
				(font
					(size 1.27 1.27)
					(thickness 0.15)
				)
				(justify left bottom)
				(hide yes)
			)
		)
		(instances
			(project "jetson-agx-thor-baseboard"
				(path ""
					(reference "A2")
					(unit 1)
				)
			)
		)
	)
	(symbol
		(lib_id "antmicroResistors0402:R_0R_0402")
		(at 318.77 129.54 0)
		(unit 1)
		(exclude_from_sim no)
		(in_bom yes)
		(on_board yes)
		(dnp no)
		(property "Reference" "R264"
			(at 316.484 128.27 0)
			(effects
				(font
					(size 1.27 1.27)
					(thickness 0.15)
				)
			)
		)
		(property "Value" "R_0R_0402"
			(at 339.09 142.24 0)
			(effects
				(font
					(size 1.27 1.27)
					(thickness 0.15)
				)
				(justify left bottom)
				(hide yes)
			)
		)
		(property "Footprint" "antmicro-footprints:R_0402_1005Metric"
			(at 339.09 144.78 0)
			(effects
				(font
					(size 1.27 1.27)
					(thickness 0.15)
				)
				(justify left bottom)
				(hide yes)
			)
		)
		(property "Datasheet" "https://industrial.panasonic.com/cdbs/www-data/pdf/RDA0000/AOA0000C301.pdf"
			(at 339.09 147.32 0)
			(effects
				(font
					(size 1.27 1.27)
					(thickness 0.15)
				)
				(justify left bottom)
				(hide yes)
			)
		)
		(property "Description" "SMD Chip Resistor, Jumper, 0 ohm, 100 mW, 0402 [1005 Metric], Thick Film, General Purpose"
			(at 318.77 129.54 0)
			(effects
				(font
					(size 1.27 1.27)
				)
				(hide yes)
			)
		)
		(property "MPN" "ERJ2GE0R00X"
			(at 339.09 149.86 0)
			(effects
				(font
					(size 1.27 1.27)
					(thickness 0.15)
				)
				(justify left bottom)
				(hide yes)
			)
		)
		(property "Manufacturer" "Panasonic"
			(at 339.09 152.4 0)
			(effects
				(font
					(size 1.27 1.27)
					(thickness 0.15)
				)
				(justify left bottom)
				(hide yes)
			)
		)
		(property "License" "Apache-2.0"
			(at 339.09 154.94 0)
			(effects
				(font
					(size 1.27 1.27)
					(thickness 0.15)
				)
				(justify left bottom)
				(hide yes)
			)
		)
		(property "Val" "0R"
			(at 325.12 128.27 0)
			(effects
				(font
					(size 1.27 1.27)
					(thickness 0.15)
				)
			)
		)
		(property "Tolerance" "~"
			(at 339.09 139.7 0)
			(effects
				(font
					(size 1.27 1.27)
				)
				(justify left bottom)
				(hide yes)
			)
		)
		(property "Current" "1A"
			(at 321.31 125.73 0)
			(effects
				(font
					(size 1.27 1.27)
					(thickness 0.15)
				)
				(hide yes)
			)
		)
		(property "Author" "Antmicro"
			(at 339.09 157.48 0)
			(effects
				(font
					(size 1.27 1.27)
					(thickness 0.15)
				)
				(justify left bottom)
				(hide yes)
			)
		)
		(property "Public" "False"
			(at 339.09 160.02 0)
			(effects
				(font
					(size 1.27 1.27)
				)
				(justify left bottom)
				(hide yes)
			)
		)
		(pin "1"
		)
		(pin "2"
		)
		(instances
			(project "jetson-agx-thor-baseboard"
				(path ""
					(reference "R264")
					(unit 1)
				)
			)
		)
	)
	(symbol
		(lib_id "antmicroCapacitors0402:C_220n_0402")
		(at 220.98 111.76 0)
		(unit 1)
		(exclude_from_sim no)
		(in_bom yes)
		(on_board yes)
		(dnp no)
		(property "Reference" "C194"
			(at 220.218 110.49 0)
			(effects
				(font
					(size 1.27 1.27)
					(thickness 0.15)
				)
			)
		)
		(property "Value" "C_220n_0402"
			(at 236.22 134.62 0)
			(effects
				(font
					(size 1.27 1.27)
					(thickness 0.15)
				)
				(justify left bottom)
				(hide yes)
			)
		)
		(property "Footprint" "antmicro-footprints:C_0402_1005Metric"
			(at 236.22 137.16 0)
			(effects
				(font
					(size 1.27 1.27)
					(thickness 0.15)
				)
				(justify left bottom)
				(hide yes)
			)
		)
		(property "Datasheet" "https://www.yageo.com/en/Chart/Download/pdf/CC0402KRX5R6BB224"
			(at 236.22 139.7 0)
			(effects
				(font
					(size 1.27 1.27)
					(thickness 0.15)
				)
				(justify left bottom)
				(hide yes)
			)
		)
		(property "Description" "SMD Multilayer Ceramic Capacitor, 0.22 µF, 10 V, 0402 [1005 Metric], ± 10%, X5R, CC Series"
			(at 220.98 111.76 0)
			(effects
				(font
					(size 1.27 1.27)
				)
				(hide yes)
			)
		)
		(property "MPN" "CC0402KRX5R6BB224"
			(at 236.22 142.24 0)
			(effects
				(font
					(size 1.27 1.27)
					(thickness 0.15)
				)
				(justify left bottom)
				(hide yes)
			)
		)
		(property "Val" "220n"
			(at 227.33 110.49 0)
			(effects
				(font
					(size 1.27 1.27)
					(thickness 0.15)
				)
			)
		)
		(property "Voltage" "25V"
			(at 236.22 121.92 0)
			(effects
				(font
					(size 1.27 1.27)
					(thickness 0.15)
				)
				(justify left bottom)
				(hide yes)
			)
		)
		(property "Dielectric" "X7R"
			(at 236.22 124.46 0)
			(effects
				(font
					(size 1.27 1.27)
					(thickness 0.15)
				)
				(justify left bottom)
				(hide yes)
			)
		)
		(property "Manufacturer" "YAGEO"
			(at 236.22 127 0)
			(effects
				(font
					(size 1.27 1.27)
					(thickness 0.15)
				)
				(justify left bottom)
				(hide yes)
			)
		)
		(property "License" "Apache-2.0"
			(at 236.22 129.54 0)
			(effects
				(font
					(size 1.27 1.27)
					(thickness 0.15)
				)
				(justify left bottom)
				(hide yes)
			)
		)
		(property "Author" "Antmicro"
			(at 236.22 132.08 0)
			(effects
				(font
					(size 1.27 1.27)
					(thickness 0.15)
				)
				(justify left bottom)
				(hide yes)
			)
		)
		(property "Public" "False"
			(at 241.3 144.78 0)
			(effects
				(font
					(size 1.27 1.27)
				)
				(justify left bottom)
				(hide yes)
			)
		)
		(pin "2"
		)
		(pin "1"
		)
		(instances
			(project "jetson-agx-thor-baseboard"
				(path ""
					(reference "C194")
					(unit 1)
				)
			)
		)
	)
	(symbol
		(lib_id "antmicroCapacitors0603:C_22u_16V_0603")
		(at 157.48 100.33 90)
		(mirror x)
		(unit 1)
		(exclude_from_sim no)
		(in_bom yes)
		(on_board yes)
		(dnp no)
		(fields_autoplaced yes)
		(property "Reference" "C192"
			(at 160.02 101.6063 90)
			(effects
				(font
					(size 1.27 1.27)
				)
				(justify right)
			)
		)
		(property "Value" "C_22u_16V_0603"
			(at 167.64 120.65 0)
			(effects
				(font
					(size 1.27 1.27)
					(thickness 0.15)
				)
				(justify left bottom)
				(hide yes)
			)
		)
		(property "Footprint" "antmicro-footprints:C_0603_1608Metric_EIA"
			(at 170.18 120.65 0)
			(effects
				(font
					(size 1.27 1.27)
					(thickness 0.15)
				)
				(justify left bottom)
				(hide yes)
			)
		)
		(property "Datasheet" "https://product.samsungsem.com/mlcc/CL10A226MO7JZN.do"
			(at 172.72 120.65 0)
			(effects
				(font
					(size 1.27 1.27)
					(thickness 0.15)
				)
				(justify left bottom)
				(hide yes)
			)
		)
		(property "Description" "SMD Multilayer Ceramic Capacitor"
			(at 157.48 100.33 0)
			(effects
				(font
					(size 1.27 1.27)
				)
				(hide yes)
			)
		)
		(property "Manufacturer" "Samsung Electro-Mechanics"
			(at 177.8 120.65 0)
			(effects
				(font
					(size 1.27 1.27)
					(thickness 0.15)
				)
				(justify left bottom)
				(hide yes)
			)
		)
		(property "MPN" "CL10A226MO7JZNC"
			(at 175.26 120.65 0)
			(effects
				(font
					(size 1.27 1.27)
					(thickness 0.15)
				)
				(justify left bottom)
				(hide yes)
			)
		)
		(property "Val" "22u"
			(at 160.02 104.1463 90)
			(effects
				(font
					(size 1.27 1.27)
					(thickness 0.15)
				)
				(justify right)
			)
		)
		(property "License" "Apache-2.0"
			(at 180.34 120.65 0)
			(effects
				(font
					(size 1.27 1.27)
					(thickness 0.15)
				)
				(justify left bottom)
				(hide yes)
			)
		)
		(property "Author" "Antmicro"
			(at 182.88 120.65 0)
			(effects
				(font
					(size 1.27 1.27)
					(thickness 0.15)
				)
				(justify left bottom)
				(hide yes)
			)
		)
		(property "Voltage" "16V"
			(at 185.42 120.65 0)
			(effects
				(font
					(size 1.27 1.27)
				)
				(justify left bottom)
				(hide yes)
			)
		)
		(property "Dielectric" "template_dielectric"
			(at 187.96 120.65 0)
			(effects
				(font
					(size 1.27 1.27)
				)
				(justify left bottom)
				(hide yes)
			)
		)
		(pin "1"
		)
		(pin "2"
		)
		(instances
			(project "jetson-agx-thor-baseboard"
				(path ""
					(reference "C192")
					(unit 1)
				)
			)
		)
	)
	(symbol
		(lib_id "antmicroCapacitors0603:C_22u_16V_0603")
		(at 318.77 93.98 90)
		(unit 1)
		(exclude_from_sim no)
		(in_bom yes)
		(on_board yes)
		(dnp no)
		(fields_autoplaced yes)
		(property "Reference" "C170"
			(at 321.31 90.1636 90)
			(effects
				(font
					(size 1.27 1.27)
					(thickness 0.15)
				)
				(justify right)
			)
		)
		(property "Value" "C_22u_16V_0603"
			(at 328.93 73.66 0)
			(effects
				(font
					(size 1.27 1.27)
					(thickness 0.15)
				)
				(justify left bottom)
				(hide yes)
			)
		)
		(property "Footprint" "antmicro-footprints:C_0603_1608Metric_EIA"
			(at 331.47 73.66 0)
			(effects
				(font
					(size 1.27 1.27)
					(thickness 0.15)
				)
				(justify left bottom)
				(hide yes)
			)
		)
		(property "Datasheet" "https://product.samsungsem.com/mlcc/CL10A226MO7JZN.do"
			(at 334.01 73.66 0)
			(effects
				(font
					(size 1.27 1.27)
					(thickness 0.15)
				)
				(justify left bottom)
				(hide yes)
			)
		)
		(property "Description" "SMD Multilayer Ceramic Capacitor"
			(at 318.77 93.98 0)
			(effects
				(font
					(size 1.27 1.27)
				)
				(hide yes)
			)
		)
		(property "MPN" "CL10A226MO7JZNC"
			(at 336.55 73.66 0)
			(effects
				(font
					(size 1.27 1.27)
					(thickness 0.15)
				)
				(justify left bottom)
				(hide yes)
			)
		)
		(property "Manufacturer" "Samsung Electro-Mechanics"
			(at 339.09 73.66 0)
			(effects
				(font
					(size 1.27 1.27)
					(thickness 0.15)
				)
				(justify left bottom)
				(hide yes)
			)
		)
		(property "License" "Apache-2.0"
			(at 341.63 73.66 0)
			(effects
				(font
					(size 1.27 1.27)
					(thickness 0.15)
				)
				(justify left bottom)
				(hide yes)
			)
		)
		(property "Author" "Antmicro"
			(at 344.17 73.66 0)
			(effects
				(font
					(size 1.27 1.27)
					(thickness 0.15)
				)
				(justify left bottom)
				(hide yes)
			)
		)
		(property "Val" "22u"
			(at 321.31 92.7036 90)
			(effects
				(font
					(size 1.27 1.27)
					(thickness 0.15)
				)
				(justify right)
			)
		)
		(property "Voltage" "16V"
			(at 346.71 73.66 0)
			(effects
				(font
					(size 1.27 1.27)
				)
				(justify left bottom)
				(hide yes)
			)
		)
		(property "Dielectric" ""
			(at 349.25 73.66 0)
			(effects
				(font
					(size 1.27 1.27)
				)
				(justify left bottom)
				(hide yes)
			)
		)
		(pin "2"
		)
		(pin "1"
		)
		(instances
			(project "jetson-agx-thor-baseboard"
				(path ""
					(reference "C170")
					(unit 1)
				)
			)
		)
	)
	(symbol
		(lib_id "antmicroResistors0402:R_47k_0402")
		(at 92.71 96.52 90)
		(mirror x)
		(unit 1)
		(exclude_from_sim no)
		(in_bom no)
		(on_board yes)
		(dnp yes)
		(property "Reference" "R210"
			(at 93.98 97.79 90)
			(effects
				(font
					(size 1.27 1.27)
				)
				(justify right)
			)
		)
		(property "Value" "R_47k_0402"
			(at 105.41 116.84 0)
			(effects
				(font
					(size 1.27 1.27)
					(thickness 0.15)
				)
				(justify left bottom)
				(hide yes)
			)
		)
		(property "Footprint" "antmicro-footprints:R_0402_1005Metric"
			(at 107.95 116.84 0)
			(effects
				(font
					(size 1.27 1.27)
					(thickness 0.15)
				)
				(justify left bottom)
				(hide yes)
			)
		)
		(property "Datasheet" "https://www.bourns.com/docs/product-datasheets/cr.pdf"
			(at 110.49 116.84 0)
			(effects
				(font
					(size 1.27 1.27)
					(thickness 0.15)
				)
				(justify left bottom)
				(hide yes)
			)
		)
		(property "Description" "SMD Chip Resistor, 47 kohm, ± 1%, 62.5 mW, 0402 [1005 Metric], Thick Film, General Purpose"
			(at 92.71 96.52 0)
			(effects
				(font
					(size 1.27 1.27)
				)
				(hide yes)
			)
		)
		(property "Manufacturer" "Bourns"
			(at 115.57 116.84 0)
			(effects
				(font
					(size 1.27 1.27)
					(thickness 0.15)
				)
				(justify left bottom)
				(hide yes)
			)
		)
		(property "MPN" "CR0402-FX-4702GLF"
			(at 113.03 116.84 0)
			(effects
				(font
					(size 1.27 1.27)
					(thickness 0.15)
				)
				(justify left bottom)
				(hide yes)
			)
		)
		(property "Val" "47k"
			(at 93.98 100.33 90)
			(effects
				(font
					(size 1.27 1.27)
					(thickness 0.15)
				)
				(justify right)
			)
		)
		(property "License" "Apache-2.0"
			(at 118.11 116.84 0)
			(effects
				(font
					(size 1.27 1.27)
					(thickness 0.15)
				)
				(justify left bottom)
				(hide yes)
			)
		)
		(property "Author" "Antmicro"
			(at 120.65 116.84 0)
			(effects
				(font
					(size 1.27 1.27)
					(thickness 0.15)
				)
				(justify left bottom)
				(hide yes)
			)
		)
		(property "Tolerance" "1%"
			(at 102.87 116.84 0)
			(effects
				(font
					(size 1.27 1.27)
				)
				(justify left bottom)
				(hide yes)
			)
		)
		(pin "1"
		)
		(pin "2"
		)
		(instances
			(project "jetson-agx-thor-baseboard"
				(path ""
					(reference "R210")
					(unit 1)
				)
			)
		)
	)
	(symbol
		(lib_id "antmicroResistors0402:R_0R_0402")
		(at 318.77 132.08 0)
		(unit 1)
		(exclude_from_sim no)
		(in_bom yes)
		(on_board yes)
		(dnp no)
		(property "Reference" "R226"
			(at 316.484 130.81 0)
			(effects
				(font
					(size 1.27 1.27)
					(thickness 0.15)
				)
			)
		)
		(property "Value" "R_0R_0402"
			(at 339.09 144.78 0)
			(effects
				(font
					(size 1.27 1.27)
					(thickness 0.15)
				)
				(justify left bottom)
				(hide yes)
			)
		)
		(property "Footprint" "antmicro-footprints:R_0402_1005Metric"
			(at 339.09 147.32 0)
			(effects
				(font
					(size 1.27 1.27)
					(thickness 0.15)
				)
				(justify left bottom)
				(hide yes)
			)
		)
		(property "Datasheet" "https://industrial.panasonic.com/cdbs/www-data/pdf/RDA0000/AOA0000C301.pdf"
			(at 339.09 149.86 0)
			(effects
				(font
					(size 1.27 1.27)
					(thickness 0.15)
				)
				(justify left bottom)
				(hide yes)
			)
		)
		(property "Description" "SMD Chip Resistor, Jumper, 0 ohm, 100 mW, 0402 [1005 Metric], Thick Film, General Purpose"
			(at 318.77 132.08 0)
			(effects
				(font
					(size 1.27 1.27)
				)
				(hide yes)
			)
		)
		(property "MPN" "ERJ2GE0R00X"
			(at 339.09 152.4 0)
			(effects
				(font
					(size 1.27 1.27)
					(thickness 0.15)
				)
				(justify left bottom)
				(hide yes)
			)
		)
		(property "Manufacturer" "Panasonic"
			(at 339.09 154.94 0)
			(effects
				(font
					(size 1.27 1.27)
					(thickness 0.15)
				)
				(justify left bottom)
				(hide yes)
			)
		)
		(property "License" "Apache-2.0"
			(at 339.09 157.48 0)
			(effects
				(font
					(size 1.27 1.27)
					(thickness 0.15)
				)
				(justify left bottom)
				(hide yes)
			)
		)
		(property "Val" "0R"
			(at 325.12 130.81 0)
			(effects
				(font
					(size 1.27 1.27)
					(thickness 0.15)
				)
			)
		)
		(property "Tolerance" "~"
			(at 339.09 142.24 0)
			(effects
				(font
					(size 1.27 1.27)
				)
				(justify left bottom)
				(hide yes)
			)
		)
		(property "Current" "1A"
			(at 321.31 128.27 0)
			(effects
				(font
					(size 1.27 1.27)
					(thickness 0.15)
				)
				(hide yes)
			)
		)
		(property "Author" "Antmicro"
			(at 339.09 160.02 0)
			(effects
				(font
					(size 1.27 1.27)
					(thickness 0.15)
				)
				(justify left bottom)
				(hide yes)
			)
		)
		(property "Public" "False"
			(at 339.09 162.56 0)
			(effects
				(font
					(size 1.27 1.27)
				)
				(justify left bottom)
				(hide yes)
			)
		)
		(pin "1"
		)
		(pin "2"
		)
		(instances
			(project "jetson-agx-thor-baseboard"
				(path ""
					(reference "R226")
					(unit 1)
				)
			)
		)
	)
	(symbol
		(lib_id "antmicropower:GND")
		(at 167.64 105.41 0)
		(unit 1)
		(exclude_from_sim no)
		(in_bom yes)
		(on_board yes)
		(dnp no)
		(property "Reference" "#PWR0372"
			(at 167.64 111.76 0)
			(effects
				(font
					(size 1.27 1.27)
				)
				(justify left bottom)
				(hide yes)
			)
		)
		(property "Value" "GND"
			(at 165.735 109.855 0)
			(effects
				(font
					(size 1.27 1.27)
					(thickness 0.15)
				)
				(justify left bottom)
			)
		)
		(property "Footprint" ""
			(at 176.53 113.03 0)
			(effects
				(font
					(size 1.27 1.27)
					(thickness 0.15)
				)
				(justify left bottom)
				(hide yes)
			)
		)
		(property "Datasheet" ""
			(at 176.53 118.11 0)
			(effects
				(font
					(size 1.27 1.27)
					(thickness 0.15)
				)
				(justify left bottom)
				(hide yes)
			)
		)
		(property "Description" ""
			(at 167.64 105.41 0)
			(effects
				(font
					(size 1.27 1.27)
				)
				(hide yes)
			)
		)
		(property "Author" "Antmicro"
			(at 176.53 113.03 0)
			(effects
				(font
					(size 1.27 1.27)
					(thickness 0.15)
				)
				(justify left bottom)
				(hide yes)
			)
		)
		(property "License" "Apache-2.0"
			(at 176.53 115.57 0)
			(effects
				(font
					(size 1.27 1.27)
					(thickness 0.15)
				)
				(justify left bottom)
				(hide yes)
			)
		)
		(pin "1"
		)
		(instances
			(project "jetson-agx-thor-baseboard"
				(path ""
					(reference "#PWR0372")
					(unit 1)
				)
			)
		)
	)
	(symbol
		(lib_id "antmicropower:+3V3")
		(at 83.82 93.98 0)
		(unit 1)
		(exclude_from_sim no)
		(in_bom yes)
		(on_board yes)
		(dnp no)
		(property "Reference" "#PWR0364"
			(at 83.82 97.79 0)
			(effects
				(font
					(size 1.27 1.27)
				)
				(justify left bottom)
				(hide yes)
			)
		)
		(property "Value" "+3V3"
			(at 80.645 90.17 0)
			(effects
				(font
					(size 1.27 1.27)
					(thickness 0.15)
				)
				(justify left)
			)
		)
		(property "Footprint" ""
			(at 99.06 101.6 0)
			(effects
				(font
					(size 1.27 1.27)
					(thickness 0.15)
				)
				(justify left bottom)
				(hide yes)
			)
		)
		(property "Datasheet" ""
			(at 99.06 104.14 0)
			(effects
				(font
					(size 1.27 1.27)
					(thickness 0.15)
				)
				(justify left bottom)
				(hide yes)
			)
		)
		(property "Description" ""
			(at 83.82 93.98 0)
			(effects
				(font
					(size 1.27 1.27)
				)
				(hide yes)
			)
		)
		(property "Author" "Antmicro"
			(at 99.06 96.52 0)
			(effects
				(font
					(size 1.27 1.27)
					(thickness 0.15)
				)
				(justify left bottom)
				(hide yes)
			)
		)
		(property "License" "Apache-2.0"
			(at 99.06 99.06 0)
			(effects
				(font
					(size 1.27 1.27)
					(thickness 0.15)
				)
				(justify left bottom)
				(hide yes)
			)
		)
		(pin "1"
		)
		(instances
			(project "jetson-agx-thor-baseboard"
				(path ""
					(reference "#PWR0364")
					(unit 1)
				)
			)
		)
	)
	(symbol
		(lib_id "antmicroCapacitors0402:C_220n_0402")
		(at 58.42 124.46 0)
		(unit 1)
		(exclude_from_sim no)
		(in_bom yes)
		(on_board yes)
		(dnp no)
		(property "Reference" "C181"
			(at 57.658 123.19 0)
			(effects
				(font
					(size 1.27 1.27)
					(thickness 0.15)
				)
			)
		)
		(property "Value" "C_220n_0402"
			(at 73.66 147.32 0)
			(effects
				(font
					(size 1.27 1.27)
					(thickness 0.15)
				)
				(justify left bottom)
				(hide yes)
			)
		)
		(property "Footprint" "antmicro-footprints:C_0402_1005Metric"
			(at 73.66 149.86 0)
			(effects
				(font
					(size 1.27 1.27)
					(thickness 0.15)
				)
				(justify left bottom)
				(hide yes)
			)
		)
		(property "Datasheet" "https://www.yageo.com/en/Chart/Download/pdf/CC0402KRX5R6BB224"
			(at 73.66 152.4 0)
			(effects
				(font
					(size 1.27 1.27)
					(thickness 0.15)
				)
				(justify left bottom)
				(hide yes)
			)
		)
		(property "Description" "SMD Multilayer Ceramic Capacitor, 0.22 µF, 10 V, 0402 [1005 Metric], ± 10%, X5R, CC Series"
			(at 58.42 124.46 0)
			(effects
				(font
					(size 1.27 1.27)
				)
				(hide yes)
			)
		)
		(property "MPN" "CC0402KRX5R6BB224"
			(at 73.66 154.94 0)
			(effects
				(font
					(size 1.27 1.27)
					(thickness 0.15)
				)
				(justify left bottom)
				(hide yes)
			)
		)
		(property "Val" "220n"
			(at 64.77 123.19 0)
			(effects
				(font
					(size 1.27 1.27)
					(thickness 0.15)
				)
			)
		)
		(property "Voltage" "25V"
			(at 73.66 134.62 0)
			(effects
				(font
					(size 1.27 1.27)
					(thickness 0.15)
				)
				(justify left bottom)
				(hide yes)
			)
		)
		(property "Dielectric" "X7R"
			(at 73.66 137.16 0)
			(effects
				(font
					(size 1.27 1.27)
					(thickness 0.15)
				)
				(justify left bottom)
				(hide yes)
			)
		)
		(property "Manufacturer" "YAGEO"
			(at 73.66 139.7 0)
			(effects
				(font
					(size 1.27 1.27)
					(thickness 0.15)
				)
				(justify left bottom)
				(hide yes)
			)
		)
		(property "License" "Apache-2.0"
			(at 73.66 142.24 0)
			(effects
				(font
					(size 1.27 1.27)
					(thickness 0.15)
				)
				(justify left bottom)
				(hide yes)
			)
		)
		(property "Author" "Antmicro"
			(at 73.66 144.78 0)
			(effects
				(font
					(size 1.27 1.27)
					(thickness 0.15)
				)
				(justify left bottom)
				(hide yes)
			)
		)
		(property "Public" "False"
			(at 78.74 157.48 0)
			(effects
				(font
					(size 1.27 1.27)
				)
				(justify left bottom)
				(hide yes)
			)
		)
		(pin "2"
		)
		(pin "1"
		)
		(instances
			(project "jetson-agx-thor-baseboard"
				(path ""
					(reference "C181")
					(unit 1)
				)
			)
		)
	)
	(symbol
		(lib_id "antmicroLEDIndicationDiscrete:LED_G_0603_LTST-C190GKT")
		(at 363.22 176.53 90)
		(unit 1)
		(exclude_from_sim no)
		(in_bom yes)
		(on_board yes)
		(dnp no)
		(fields_autoplaced yes)
		(property "Reference" "D33"
			(at 359.41 172.72 90)
			(effects
				(font
					(size 1.27 1.27)
				)
				(justify left)
			)
		)
		(property "Value" "LED_G_0603_LTST-C190GKT"
			(at 370.84 153.67 0)
			(effects
				(font
					(size 1.27 1.27)
					(thickness 0.15)
				)
				(justify left bottom)
				(hide yes)
			)
		)
		(property "Footprint" "antmicro-footprints:LED_0603_1608Metric_G"
			(at 373.38 153.67 0)
			(effects
				(font
					(size 1.27 1.27)
					(thickness 0.15)
				)
				(justify left bottom)
				(hide yes)
			)
		)
		(property "Datasheet" "https://media.digikey.com/pdf/Data%20Sheets/Lite-On%20PDFs/LTST-C190GKT.pdf"
			(at 375.92 153.67 0)
			(effects
				(font
					(size 1.27 1.27)
					(thickness 0.15)
				)
				(justify left bottom)
				(hide yes)
			)
		)
		(property "Description" "LED, Green, SMD, 0603, 20 mA, 2.1 V, 569 nm"
			(at 363.22 176.53 0)
			(effects
				(font
					(size 1.27 1.27)
				)
				(hide yes)
			)
		)
		(property "MPN" "LTST-C190GKT"
			(at 366.395 182.88 0)
			(effects
				(font
					(size 1.27 1.27)
					(thickness 0.15)
				)
				(justify left)
				(hide yes)
			)
		)
		(property "Manufacturer" "Lite-On"
			(at 381 153.67 0)
			(effects
				(font
					(size 1.27 1.27)
					(thickness 0.15)
				)
				(justify left bottom)
				(hide yes)
			)
		)
		(property "Author" "Antmicro"
			(at 383.54 153.67 0)
			(effects
				(font
					(size 1.27 1.27)
					(thickness 0.15)
				)
				(justify left bottom)
				(hide yes)
			)
		)
		(property "License" "Apache-2.0"
			(at 386.08 153.67 0)
			(effects
				(font
					(size 1.27 1.27)
					(thickness 0.15)
				)
				(justify left bottom)
				(hide yes)
			)
		)
		(property "Public" "False"
			(at 381 156.21 0)
			(effects
				(font
					(size 1.27 1.27)
				)
				(justify left bottom)
				(hide yes)
			)
		)
		(property "Color" "Green"
			(at 359.41 175.26 90)
			(effects
				(font
					(size 1.27 1.27)
				)
				(justify left)
			)
		)
		(pin "1"
		)
		(pin "2"
		)
		(instances
			(project "jetson-agx-thor-baseboard"
				(path ""
					(reference "D33")
					(unit 1)
				)
			)
		)
	)
	(symbol
		(lib_id "antmicropower:+3V3")
		(at 327.66 83.82 0)
		(unit 1)
		(exclude_from_sim no)
		(in_bom yes)
		(on_board yes)
		(dnp no)
		(property "Reference" "#PWR0380"
			(at 327.66 87.63 0)
			(effects
				(font
					(size 1.27 1.27)
				)
				(hide yes)
			)
		)
		(property "Value" "+3V3"
			(at 327.66 80.01 0)
			(effects
				(font
					(size 1.27 1.27)
				)
			)
		)
		(property "Footprint" ""
			(at 327.66 83.82 0)
			(effects
				(font
					(size 1.27 1.27)
				)
				(hide yes)
			)
		)
		(property "Datasheet" ""
			(at 327.66 83.82 0)
			(effects
				(font
					(size 1.27 1.27)
				)
				(hide yes)
			)
		)
		(property "Description" ""
			(at 327.66 83.82 0)
			(effects
				(font
					(size 1.27 1.27)
				)
				(hide yes)
			)
		)
		(property "Author" "Antmicro"
			(at 342.9 86.36 0)
			(effects
				(font
					(size 1.27 1.27)
					(thickness 0.15)
				)
				(justify left bottom)
				(hide yes)
			)
		)
		(property "License" "Apache-2.0"
			(at 342.9 88.9 0)
			(effects
				(font
					(size 1.27 1.27)
					(thickness 0.15)
				)
				(justify left bottom)
				(hide yes)
			)
		)
		(pin "1"
		)
		(instances
			(project "jetson-agx-thor-baseboard"
				(path ""
					(reference "#PWR0380")
					(unit 1)
				)
			)
		)
	)
	(symbol
		(lib_id "antmicroResistors0402:R_0R_0402")
		(at 229.87 175.26 0)
		(unit 1)
		(exclude_from_sim no)
		(in_bom yes)
		(on_board yes)
		(dnp no)
		(property "Reference" "R219"
			(at 227.33 176.53 0)
			(effects
				(font
					(size 1.27 1.27)
					(thickness 0.15)
				)
			)
		)
		(property "Value" "R_0R_0402"
			(at 250.19 187.96 0)
			(effects
				(font
					(size 1.27 1.27)
					(thickness 0.15)
				)
				(justify left bottom)
				(hide yes)
			)
		)
		(property "Footprint" "antmicro-footprints:R_0402_1005Metric"
			(at 250.19 190.5 0)
			(effects
				(font
					(size 1.27 1.27)
					(thickness 0.15)
				)
				(justify left bottom)
				(hide yes)
			)
		)
		(property "Datasheet" "https://industrial.panasonic.com/cdbs/www-data/pdf/RDA0000/AOA0000C301.pdf"
			(at 250.19 193.04 0)
			(effects
				(font
					(size 1.27 1.27)
					(thickness 0.15)
				)
				(justify left bottom)
				(hide yes)
			)
		)
		(property "Description" "SMD Chip Resistor, Jumper, 0 ohm, 100 mW, 0402 [1005 Metric], Thick Film, General Purpose"
			(at 229.87 175.26 0)
			(effects
				(font
					(size 1.27 1.27)
				)
				(hide yes)
			)
		)
		(property "MPN" "ERJ2GE0R00X"
			(at 250.19 195.58 0)
			(effects
				(font
					(size 1.27 1.27)
					(thickness 0.15)
				)
				(justify left bottom)
				(hide yes)
			)
		)
		(property "Manufacturer" "Panasonic"
			(at 250.19 198.12 0)
			(effects
				(font
					(size 1.27 1.27)
					(thickness 0.15)
				)
				(justify left bottom)
				(hide yes)
			)
		)
		(property "License" "Apache-2.0"
			(at 250.19 200.66 0)
			(effects
				(font
					(size 1.27 1.27)
					(thickness 0.15)
				)
				(justify left bottom)
				(hide yes)
			)
		)
		(property "Val" "0R"
			(at 236.22 176.53 0)
			(effects
				(font
					(size 1.27 1.27)
					(thickness 0.15)
				)
			)
		)
		(property "Tolerance" "~"
			(at 250.19 185.42 0)
			(effects
				(font
					(size 1.27 1.27)
				)
				(justify left bottom)
				(hide yes)
			)
		)
		(property "Current" "1A"
			(at 232.41 172.085 0)
			(effects
				(font
					(size 1.27 1.27)
					(thickness 0.15)
				)
				(hide yes)
			)
		)
		(property "Author" "Antmicro"
			(at 250.19 203.2 0)
			(effects
				(font
					(size 1.27 1.27)
					(thickness 0.15)
				)
				(justify left bottom)
				(hide yes)
			)
		)
		(property "Public" "False"
			(at 250.19 205.74 0)
			(effects
				(font
					(size 1.27 1.27)
				)
				(justify left bottom)
				(hide yes)
			)
		)
		(pin "1"
		)
		(pin "2"
		)
		(instances
			(project "jetson-agx-thor-baseboard"
				(path ""
					(reference "R219")
					(unit 1)
				)
			)
		)
	)
	(symbol
		(lib_id "antmicroCapacitors0402:C_220n_0402")
		(at 58.42 154.94 0)
		(unit 1)
		(exclude_from_sim no)
		(in_bom yes)
		(on_board yes)
		(dnp no)
		(property "Reference" "C183"
			(at 57.658 153.67 0)
			(effects
				(font
					(size 1.27 1.27)
					(thickness 0.15)
				)
			)
		)
		(property "Value" "C_220n_0402"
			(at 73.66 177.8 0)
			(effects
				(font
					(size 1.27 1.27)
					(thickness 0.15)
				)
				(justify left bottom)
				(hide yes)
			)
		)
		(property "Footprint" "antmicro-footprints:C_0402_1005Metric"
			(at 73.66 180.34 0)
			(effects
				(font
					(size 1.27 1.27)
					(thickness 0.15)
				)
				(justify left bottom)
				(hide yes)
			)
		)
		(property "Datasheet" "https://www.yageo.com/en/Chart/Download/pdf/CC0402KRX5R6BB224"
			(at 73.66 182.88 0)
			(effects
				(font
					(size 1.27 1.27)
					(thickness 0.15)
				)
				(justify left bottom)
				(hide yes)
			)
		)
		(property "Description" "SMD Multilayer Ceramic Capacitor, 0.22 µF, 10 V, 0402 [1005 Metric], ± 10%, X5R, CC Series"
			(at 58.42 154.94 0)
			(effects
				(font
					(size 1.27 1.27)
				)
				(hide yes)
			)
		)
		(property "MPN" "CC0402KRX5R6BB224"
			(at 73.66 185.42 0)
			(effects
				(font
					(size 1.27 1.27)
					(thickness 0.15)
				)
				(justify left bottom)
				(hide yes)
			)
		)
		(property "Val" "220n"
			(at 64.77 153.67 0)
			(effects
				(font
					(size 1.27 1.27)
					(thickness 0.15)
				)
			)
		)
		(property "Voltage" "25V"
			(at 73.66 165.1 0)
			(effects
				(font
					(size 1.27 1.27)
					(thickness 0.15)
				)
				(justify left bottom)
				(hide yes)
			)
		)
		(property "Dielectric" "X7R"
			(at 73.66 167.64 0)
			(effects
				(font
					(size 1.27 1.27)
					(thickness 0.15)
				)
				(justify left bottom)
				(hide yes)
			)
		)
		(property "Manufacturer" "YAGEO"
			(at 73.66 170.18 0)
			(effects
				(font
					(size 1.27 1.27)
					(thickness 0.15)
				)
				(justify left bottom)
				(hide yes)
			)
		)
		(property "License" "Apache-2.0"
			(at 73.66 172.72 0)
			(effects
				(font
					(size 1.27 1.27)
					(thickness 0.15)
				)
				(justify left bottom)
				(hide yes)
			)
		)
		(property "Author" "Antmicro"
			(at 73.66 175.26 0)
			(effects
				(font
					(size 1.27 1.27)
					(thickness 0.15)
				)
				(justify left bottom)
				(hide yes)
			)
		)
		(property "Public" "False"
			(at 78.74 187.96 0)
			(effects
				(font
					(size 1.27 1.27)
				)
				(justify left bottom)
				(hide yes)
			)
		)
		(pin "2"
		)
		(pin "1"
		)
		(instances
			(project "jetson-agx-thor-baseboard"
				(path ""
					(reference "C183")
					(unit 1)
				)
			)
		)
	)
	(symbol
		(lib_id "antmicroResistors0402:R_0R_0402")
		(at 318.77 106.68 0)
		(unit 1)
		(exclude_from_sim no)
		(in_bom yes)
		(on_board yes)
		(dnp no)
		(property "Reference" "R223"
			(at 316.484 105.41 0)
			(effects
				(font
					(size 1.27 1.27)
					(thickness 0.15)
				)
			)
		)
		(property "Value" "R_0R_0402"
			(at 339.09 119.38 0)
			(effects
				(font
					(size 1.27 1.27)
					(thickness 0.15)
				)
				(justify left bottom)
				(hide yes)
			)
		)
		(property "Footprint" "antmicro-footprints:R_0402_1005Metric"
			(at 339.09 121.92 0)
			(effects
				(font
					(size 1.27 1.27)
					(thickness 0.15)
				)
				(justify left bottom)
				(hide yes)
			)
		)
		(property "Datasheet" "https://industrial.panasonic.com/cdbs/www-data/pdf/RDA0000/AOA0000C301.pdf"
			(at 339.09 124.46 0)
			(effects
				(font
					(size 1.27 1.27)
					(thickness 0.15)
				)
				(justify left bottom)
				(hide yes)
			)
		)
		(property "Description" "SMD Chip Resistor, Jumper, 0 ohm, 100 mW, 0402 [1005 Metric], Thick Film, General Purpose"
			(at 318.77 106.68 0)
			(effects
				(font
					(size 1.27 1.27)
				)
				(hide yes)
			)
		)
		(property "MPN" "ERJ2GE0R00X"
			(at 339.09 127 0)
			(effects
				(font
					(size 1.27 1.27)
					(thickness 0.15)
				)
				(justify left bottom)
				(hide yes)
			)
		)
		(property "Manufacturer" "Panasonic"
			(at 339.09 129.54 0)
			(effects
				(font
					(size 1.27 1.27)
					(thickness 0.15)
				)
				(justify left bottom)
				(hide yes)
			)
		)
		(property "License" "Apache-2.0"
			(at 339.09 132.08 0)
			(effects
				(font
					(size 1.27 1.27)
					(thickness 0.15)
				)
				(justify left bottom)
				(hide yes)
			)
		)
		(property "Val" "0R"
			(at 325.12 105.41 0)
			(effects
				(font
					(size 1.27 1.27)
					(thickness 0.15)
				)
			)
		)
		(property "Tolerance" "~"
			(at 339.09 116.84 0)
			(effects
				(font
					(size 1.27 1.27)
				)
				(justify left bottom)
				(hide yes)
			)
		)
		(property "Current" "1A"
			(at 321.31 102.87 0)
			(effects
				(font
					(size 1.27 1.27)
					(thickness 0.15)
				)
				(hide yes)
			)
		)
		(property "Author" "Antmicro"
			(at 339.09 134.62 0)
			(effects
				(font
					(size 1.27 1.27)
					(thickness 0.15)
				)
				(justify left bottom)
				(hide yes)
			)
		)
		(property "Public" "False"
			(at 339.09 137.16 0)
			(effects
				(font
					(size 1.27 1.27)
				)
				(justify left bottom)
				(hide yes)
			)
		)
		(pin "1"
		)
		(pin "2"
		)
		(instances
			(project "jetson-agx-thor-baseboard"
				(path ""
					(reference "R223")
					(unit 1)
				)
			)
		)
	)
	(symbol
		(lib_id "antmicroCapacitors0402:C_100n_0402")
		(at 93.98 264.16 90)
		(mirror x)
		(unit 1)
		(exclude_from_sim no)
		(in_bom yes)
		(on_board yes)
		(dnp no)
		(fields_autoplaced yes)
		(property "Reference" "C189"
			(at 91.44 265.4363 90)
			(effects
				(font
					(size 1.27 1.27)
				)
				(justify left)
			)
		)
		(property "Value" "C_100n_0402"
			(at 104.14 284.48 0)
			(effects
				(font
					(size 1.27 1.27)
					(thickness 0.15)
				)
				(justify left bottom)
				(hide yes)
			)
		)
		(property "Footprint" "antmicro-footprints:C_0402_1005Metric"
			(at 106.68 284.48 0)
			(effects
				(font
					(size 1.27 1.27)
					(thickness 0.15)
				)
				(justify left bottom)
				(hide yes)
			)
		)
		(property "Datasheet" "https://www.murata.com/products/productdetail?partno=GRM155R61H104KE14%23"
			(at 109.22 284.48 0)
			(effects
				(font
					(size 1.27 1.27)
					(thickness 0.15)
				)
				(justify left bottom)
				(hide yes)
			)
		)
		(property "Description" "SMD Multilayer Ceramic Capacitor, 0.1 µF, 50 V, 0402 [1005 Metric], ± 10%, X5R, GRM Series"
			(at 93.98 264.16 0)
			(effects
				(font
					(size 1.27 1.27)
				)
				(hide yes)
			)
		)
		(property "Manufacturer" "Murata"
			(at 114.3 284.48 0)
			(effects
				(font
					(size 1.27 1.27)
					(thickness 0.15)
				)
				(justify left bottom)
				(hide yes)
			)
		)
		(property "MPN" "GRM155R61H104KE14D"
			(at 111.76 284.48 0)
			(effects
				(font
					(size 1.27 1.27)
					(thickness 0.15)
				)
				(justify left bottom)
				(hide yes)
			)
		)
		(property "Val" "100n"
			(at 91.44 267.9763 90)
			(effects
				(font
					(size 1.27 1.27)
					(thickness 0.15)
				)
				(justify left)
			)
		)
		(property "License" "Apache-2.0"
			(at 116.84 284.48 0)
			(effects
				(font
					(size 1.27 1.27)
					(thickness 0.15)
				)
				(justify left bottom)
				(hide yes)
			)
		)
		(property "Author" "Antmicro"
			(at 119.38 284.48 0)
			(effects
				(font
					(size 1.27 1.27)
					(thickness 0.15)
				)
				(justify left bottom)
				(hide yes)
			)
		)
		(property "Voltage" "50V"
			(at 121.92 284.48 0)
			(effects
				(font
					(size 1.27 1.27)
				)
				(justify left bottom)
				(hide yes)
			)
		)
		(property "Dielectric" "X5R"
			(at 124.46 284.48 0)
			(effects
				(font
					(size 1.27 1.27)
				)
				(justify left bottom)
				(hide yes)
			)
		)
		(pin "1"
		)
		(pin "2"
		)
		(instances
			(project "jetson-agx-thor-baseboard"
				(path ""
					(reference "C189")
					(unit 1)
				)
			)
		)
	)
	(symbol
		(lib_id "antmicropower:GND")
		(at 309.88 95.25 0)
		(unit 1)
		(exclude_from_sim no)
		(in_bom yes)
		(on_board yes)
		(dnp no)
		(property "Reference" "#PWR0377"
			(at 309.88 101.6 0)
			(effects
				(font
					(size 1.27 1.27)
				)
				(hide yes)
			)
		)
		(property "Value" "GND"
			(at 309.88 99.06 0)
			(effects
				(font
					(size 1.27 1.27)
				)
			)
		)
		(property "Footprint" ""
			(at 309.88 95.25 0)
			(effects
				(font
					(size 1.27 1.27)
				)
				(hide yes)
			)
		)
		(property "Datasheet" ""
			(at 309.88 95.25 0)
			(effects
				(font
					(size 1.27 1.27)
				)
				(hide yes)
			)
		)
		(property "Description" ""
			(at 309.88 95.25 0)
			(effects
				(font
					(size 1.27 1.27)
				)
				(hide yes)
			)
		)
		(property "Author" "Antmicro"
			(at 318.77 102.87 0)
			(effects
				(font
					(size 1.27 1.27)
					(thickness 0.15)
				)
				(justify left bottom)
				(hide yes)
			)
		)
		(property "License" "Apache-2.0"
			(at 318.77 105.41 0)
			(effects
				(font
					(size 1.27 1.27)
					(thickness 0.15)
				)
				(justify left bottom)
				(hide yes)
			)
		)
		(pin "1"
		)
		(instances
			(project "jetson-agx-thor-baseboard"
				(path ""
					(reference "#PWR0377")
					(unit 1)
				)
			)
		)
	)
	(symbol
		(lib_id "antmicroCapacitors0402:C_220n_0402")
		(at 64.77 142.24 0)
		(unit 1)
		(exclude_from_sim no)
		(in_bom yes)
		(on_board yes)
		(dnp no)
		(property "Reference" "C186"
			(at 64.008 140.97 0)
			(effects
				(font
					(size 1.27 1.27)
					(thickness 0.15)
				)
			)
		)
		(property "Value" "C_220n_0402"
			(at 80.01 165.1 0)
			(effects
				(font
					(size 1.27 1.27)
					(thickness 0.15)
				)
				(justify left bottom)
				(hide yes)
			)
		)
		(property "Footprint" "antmicro-footprints:C_0402_1005Metric"
			(at 80.01 167.64 0)
			(effects
				(font
					(size 1.27 1.27)
					(thickness 0.15)
				)
				(justify left bottom)
				(hide yes)
			)
		)
		(property "Datasheet" "https://www.yageo.com/en/Chart/Download/pdf/CC0402KRX5R6BB224"
			(at 80.01 170.18 0)
			(effects
				(font
					(size 1.27 1.27)
					(thickness 0.15)
				)
				(justify left bottom)
				(hide yes)
			)
		)
		(property "Description" "SMD Multilayer Ceramic Capacitor, 0.22 µF, 10 V, 0402 [1005 Metric], ± 10%, X5R, CC Series"
			(at 64.77 142.24 0)
			(effects
				(font
					(size 1.27 1.27)
				)
				(hide yes)
			)
		)
		(property "MPN" "CC0402KRX5R6BB224"
			(at 80.01 172.72 0)
			(effects
				(font
					(size 1.27 1.27)
					(thickness 0.15)
				)
				(justify left bottom)
				(hide yes)
			)
		)
		(property "Val" "220n"
			(at 71.12 140.97 0)
			(effects
				(font
					(size 1.27 1.27)
					(thickness 0.15)
				)
			)
		)
		(property "Voltage" "25V"
			(at 80.01 152.4 0)
			(effects
				(font
					(size 1.27 1.27)
					(thickness 0.15)
				)
				(justify left bottom)
				(hide yes)
			)
		)
		(property "Dielectric" "X7R"
			(at 80.01 154.94 0)
			(effects
				(font
					(size 1.27 1.27)
					(thickness 0.15)
				)
				(justify left bottom)
				(hide yes)
			)
		)
		(property "Manufacturer" "YAGEO"
			(at 80.01 157.48 0)
			(effects
				(font
					(size 1.27 1.27)
					(thickness 0.15)
				)
				(justify left bottom)
				(hide yes)
			)
		)
		(property "License" "Apache-2.0"
			(at 80.01 160.02 0)
			(effects
				(font
					(size 1.27 1.27)
					(thickness 0.15)
				)
				(justify left bottom)
				(hide yes)
			)
		)
		(property "Author" "Antmicro"
			(at 80.01 162.56 0)
			(effects
				(font
					(size 1.27 1.27)
					(thickness 0.15)
				)
				(justify left bottom)
				(hide yes)
			)
		)
		(property "Public" "False"
			(at 85.09 175.26 0)
			(effects
				(font
					(size 1.27 1.27)
				)
				(justify left bottom)
				(hide yes)
			)
		)
		(pin "2"
		)
		(pin "1"
		)
		(instances
			(project "jetson-agx-thor-baseboard"
				(path ""
					(reference "C186")
					(unit 1)
				)
			)
		)
	)
)
